FILE_TYPE = MACRO_DRAWING;
SET COLOR_WIRE YELLOW;
SET COLOR_PROP MONO;
SET COLOR_DOT WHITE;
SET COLOR_ARC YELLOW;
SET COLOR_BODY GREEN;
SET COLOR_NOTE MONO;
SET PROP_DISPLAY VALUE;
SET PAGE_NUMBER P152;
FORCEADD GTL2014..1
R 2
(-5400 4050);
FORCEPROP 2 LASTPIN (-5850 3900) $PN 2
J 2
(-5860 3910);
DISPLAY 0.617021 (-5860 3910);
PAINT ORANGE (-5860 3910);
FORCEPROP 1 LAST LOCATION U9G1
J 2
(-5000 4600);
DISPLAY 0.617021 (-5000 4600);
PAINT AQUA (-5000 4600);
FORCEPROP 2 LASTPIN (-4950 4200) $PN 1
J 0
(-4940 4210);
DISPLAY 0.617021 (-4940 4210);
PAINT ORANGE (-4940 4210);
FORCEPROP 2 LASTPIN (-4950 4300) $PN 4
J 0
(-4940 4310);
DISPLAY 0.617021 (-4940 4310);
PAINT ORANGE (-4940 4310);
FORCEPROP 1 LAST MATERIAL IC
J 2
(-5000 4550);
DISPLAY 0.617021 (-5000 4550);
PAINT SKYBLUE (-5000 4550);
FORCEPROP 2 LASTPIN (-4950 4000) $PN 10
J 0
(-4940 4010);
DISPLAY 0.617021 (-4940 4010);
PAINT ORANGE (-4940 4010);
FORCEPROP 2 LASTPIN (-4950 3950) $PN 12
J 0
(-4940 3960);
DISPLAY 0.617021 (-4940 3960);
PAINT ORANGE (-4940 3960);
FORCEPROP 2 LASTPIN (-4950 3900) $PN 13
J 0
(-4940 3910);
DISPLAY 0.617021 (-4940 3910);
PAINT ORANGE (-4940 3910);
FORCEPROP 1 LAST PART_NUMBER D66151-001
J 2
(-5000 3550);
DISPLAY 0.617021 (-5000 3550);
PAINT BLUE (-5000 3550);
FORCEPROP 2 LASTPIN (-5850 3750) $PN 11
J 2
(-5860 3760);
DISPLAY 0.617021 (-5860 3760);
PAINT ORANGE (-5860 3760);
FORCEPROP 2 LASTPIN (-5850 3700) $PN 8
J 2
(-5860 3710);
DISPLAY 0.617021 (-5860 3710);
PAINT ORANGE (-5860 3710);
FORCEPROP 2 LASTPIN (-5850 3650) $PN 7
J 2
(-5860 3660);
DISPLAY 0.617021 (-5860 3660);
PAINT ORANGE (-5860 3660);
FORCEPROP 2 LASTPIN (-5850 4000) $PN 5
J 2
(-5860 4010);
DISPLAY 0.617021 (-5860 4010);
PAINT ORANGE (-5860 4010);
FORCEPROP 2 LASTPIN (-5850 3950) $PN 3
J 2
(-5860 3960);
DISPLAY 0.617021 (-5860 3960);
PAINT ORANGE (-5860 3960);
FORCEPROP 2 LASTPIN (-5850 4050) $PN 6
J 2
(-5860 4060);
DISPLAY 0.617021 (-5860 4060);
PAINT ORANGE (-5860 4060);
FORCEPROP 2 LASTPIN (-4950 4350) $PN 14
J 0
(-4940 4360);
DISPLAY 0.617021 (-4940 4360);
PAINT ORANGE (-4940 4360);
FORCEPROP 2 LASTPIN (-4950 4050) $PN 9
J 0
(-4940 4060);
DISPLAY 0.617021 (-4940 4060);
PAINT ORANGE (-4940 4060);
FORCEPROP 2 LAST SEC 1
J 0
(-5000 4650);
DISPLAY 0.680851 (-5000 4650);
PAINT MONO (-5000 4650);
DISPLAY INVISIBLE (-5000 4650);
FORCEPROP 2 LAST BOM_COST PROC_SIDEBAND
J 0
(-5000 4700);
DISPLAY 1.021277 (-5000 4700);
PAINT ORANGE (-5000 4700);
DISPLAY INVISIBLE (-5000 4700);
FORCEPROP 2 LAST SEC_TYPE SM
J 0
(-5000 4650);
DISPLAY 1.021277 (-5000 4650);
PAINT ORANGE (-5000 4650);
DISPLAY INVISIBLE (-5000 4650);
FORCEPROP 1 LAST PACK_TYPE SM
J 2
(-5000 4650);
PAINT SKYBLUE (-5000 4650);
DISPLAY INVISIBLE (-5000 4650);
FORCEPROP 2 LAST ROOM PROC_SIDEBAND
J 0
(-5000 4650);
DISPLAY 1.021277 (-5000 4650);
PAINT ORANGE (-5000 4650);
DISPLAY INVISIBLE (-5000 4650);
FORCEPROP 2 LAST CDS_LOCATION U9G1
J 2
(-5000 4600);
DISPLAY 0.617021 (-5000 4600);
PAINT AQUA (-5000 4600);
DISPLAY INVISIBLE (-5000 4600);
FORCEPROP 1 LAST PATH I1
J 2
(-5400 4550);
PAINT GREEN (-5400 4550);
DISPLAY INVISIBLE (-5400 4550);
FORCEPROP 2 LAST CDS_LIB mstr_digital
J 2
(-5400 4050);
PAINT ORANGE (-5400 4050);
DISPLAY INVISIBLE (-5400 4050);
FORCEADD OFFPAGE..2
(-1400 4250);
FORCEPROP 2 LAST $XR0 152 
J 0
(-1211 4250);
DISPLAY 0.638298 (-1211 4250);
PAINT MONO (-1211 4250);
FORCEPROP 2 LAST CDS_LIB mstr_standard
J 0
(-1400 4250);
PAINT ORANGE (-1400 4250);
DISPLAY INVISIBLE (-1400 4250);
FORCEPROP 2 LAST PATH I10
J 0
(-1350 4325);
DISPLAY 1.021277 (-1350 4325);
PAINT ORANGE (-1350 4325);
DISPLAY INVISIBLE (-1350 4325);
FORCEPROP 1 LAST OFFPAGE TRUE
J 0
(-1075 4125);
DISPLAY 0.872340 (-1075 4125);
PAINT GREEN (-1075 4125);
DISPLAY INVISIBLE (-1075 4125);
FORCEPROP 1 LAST COMMENT_BODY TRUE
J 0
(-1445 4155);
DISPLAY 0.872340 (-1445 4155);
PAINT GREEN (-1445 4155);
DISPLAY INVISIBLE (-1445 4155);
FORCEADD RES..1
(-6700 1400);
FORCEPROP 1 LAST WATTAGE 1/16W
J 2
(-6800 1350);
DISPLAY 0.617021 (-6800 1350);
PAINT SKYBLUE (-6800 1350);
FORCEPROP 1 LAST VALUE 0.0
J 2
(-6800 1400);
DISPLAY 0.617021 (-6800 1400);
PAINT SKYBLUE (-6800 1400);
FORCEPROP 1 LASTPIN (-6800 1400) $PN 1
J 0
(-6788 1412);
DISPLAY 0.787234 (-6788 1412);
PAINT ORANGE (-6788 1412);
FORCEPROP 1 LAST LOCATION R3P63
J 0
(-6750 1450);
DISPLAY 0.617021 (-6750 1450);
PAINT AQUA (-6750 1450);
FORCEPROP 1 LAST PART_NUMBER G21497-005
J 0
(-6850 1500);
DISPLAY 0.617021 (-6850 1500);
PAINT BLUE (-6850 1500);
FORCEPROP 1 LASTPIN (-6600 1400) $PN 2
J 0
(-6638 1412);
DISPLAY 0.787234 (-6638 1412);
PAINT ORANGE (-6638 1412);
FORCEPROP 1 LAST PACK_TYPE 0402
J 0
(-6550 1350);
DISPLAY 0.617021 (-6550 1350);
PAINT SKYBLUE (-6550 1350);
FORCEPROP 1 LAST MATERIAL EMPTY
J 0
(-6700 1350);
DISPLAY 0.617021 (-6700 1350);
PAINT RED (-6700 1350);
FORCEPROP 1 LAST TOLERANCE 5%
J 0
(-6775 1350);
DISPLAY 0.617021 (-6775 1350);
PAINT SKYBLUE (-6775 1350);
FORCEPROP 2 LAST SEC_TYPE 0402
J 0
(-6750 1600);
DISPLAY 1.021277 (-6750 1600);
PAINT ORANGE (-6750 1600);
DISPLAY INVISIBLE (-6750 1600);
FORCEPROP 2 LAST SEC 1
J 0
(-6750 1600);
PAINT MONO (-6750 1600);
DISPLAY INVISIBLE (-6750 1600);
FORCEPROP 1 LAST PATH I100
J 0
(-6750 1550);
DISPLAY 0.978723 (-6750 1550);
PAINT WHITE (-6750 1550);
DISPLAY INVISIBLE (-6750 1550);
FORCEPROP 2 LAST CDS_LIB mstr_discrete
J 0
(-6700 1400);
PAINT ORANGE (-6700 1400);
DISPLAY INVISIBLE (-6700 1400);
FORCEADD OFFPAGE..2
(-5250 975);
FORCEPROP 2 LAST $XR0 121 
J 0
(-5061 975);
DISPLAY 0.638298 (-5061 975);
PAINT MONO (-5061 975);
FORCEPROP 2 LAST CDS_LIB mstr_standard
J 0
(-5250 975);
PAINT ORANGE (-5250 975);
DISPLAY INVISIBLE (-5250 975);
FORCEPROP 2 LAST PATH I101
J 0
(-5075 1050);
DISPLAY 1.021277 (-5075 1050);
PAINT ORANGE (-5075 1050);
DISPLAY INVISIBLE (-5075 1050);
FORCEPROP 1 LAST OFFPAGE TRUE
J 0
(-4925 850);
DISPLAY 0.872340 (-4925 850);
PAINT GREEN (-4925 850);
DISPLAY INVISIBLE (-4925 850);
FORCEPROP 1 LAST COMMENT_BODY TRUE
J 0
(-5295 880);
DISPLAY 0.872340 (-5295 880);
PAINT GREEN (-5295 880);
DISPLAY INVISIBLE (-5295 880);
FORCEADD RES..1
(-6700 975);
FORCEPROP 1 LASTPIN (-6800 975) $PN 1
J 0
(-6788 987);
DISPLAY 0.787234 (-6788 987);
PAINT ORANGE (-6788 987);
FORCEPROP 1 LASTPIN (-6600 975) $PN 2
J 0
(-6638 987);
DISPLAY 0.787234 (-6638 987);
PAINT ORANGE (-6638 987);
FORCEPROP 1 LAST PACK_TYPE 0402
J 0
(-6550 925);
DISPLAY 0.617021 (-6550 925);
PAINT SKYBLUE (-6550 925);
FORCEPROP 1 LAST MATERIAL EMPTY
J 0
(-6700 925);
DISPLAY 0.617021 (-6700 925);
PAINT RED (-6700 925);
FORCEPROP 1 LAST PART_NUMBER G21497-005
J 0
(-6850 1075);
DISPLAY 0.617021 (-6850 1075);
PAINT BLUE (-6850 1075);
FORCEPROP 1 LAST LOCATION R2U45
J 0
(-6750 1025);
DISPLAY 0.617021 (-6750 1025);
PAINT AQUA (-6750 1025);
FORCEPROP 1 LAST TOLERANCE 5%
J 0
(-6775 925);
DISPLAY 0.617021 (-6775 925);
PAINT SKYBLUE (-6775 925);
FORCEPROP 1 LAST VALUE 0.0
J 2
(-6800 975);
DISPLAY 0.617021 (-6800 975);
PAINT SKYBLUE (-6800 975);
FORCEPROP 1 LAST WATTAGE 1/16W
J 2
(-6800 925);
DISPLAY 0.617021 (-6800 925);
PAINT SKYBLUE (-6800 925);
FORCEPROP 2 LAST SEC_TYPE 0402
J 0
(-6750 1175);
DISPLAY 1.021277 (-6750 1175);
PAINT ORANGE (-6750 1175);
DISPLAY INVISIBLE (-6750 1175);
FORCEPROP 2 LAST SEC 1
J 0
(-6750 1175);
PAINT MONO (-6750 1175);
DISPLAY INVISIBLE (-6750 1175);
FORCEPROP 1 LAST PATH I102
J 0
(-6750 1125);
DISPLAY 0.978723 (-6750 1125);
PAINT WHITE (-6750 1125);
DISPLAY INVISIBLE (-6750 1125);
FORCEPROP 2 LAST CDS_LIB mstr_discrete
J 0
(-6700 975);
PAINT ORANGE (-6700 975);
DISPLAY INVISIBLE (-6700 975);
FORCEADD P3V3..1
(-2550 2300);
FORCEPROP 3 LASTPIN (-2550 2250) SIG_NAME P3V3\g
J 0
(-2540 2260);
DISPLAY 0.659574 (-2540 2260);
PAINT MONO (-2540 2260);
DISPLAY INVISIBLE (-2540 2260);
FORCEPROP 1 LAST HDL_POWER P3V3
J 0
(-2875 2175);
DISPLAY 0.872340 (-2875 2175);
PAINT ORANGE (-2875 2175);
DISPLAY INVISIBLE (-2875 2175);
FORCEPROP 1 LAST BODY_TYPE PLUMBING
J 0
(-2595 2257);
DISPLAY 0.340426 (-2595 2257);
PAINT GREEN (-2595 2257);
DISPLAY INVISIBLE (-2595 2257);
FORCEPROP 1 LAST SIZE 1B
J 0
(-2505 2322);
DISPLAY 0.340426 (-2505 2322);
PAINT GREEN (-2505 2322);
DISPLAY INVISIBLE (-2505 2322);
FORCEPROP 2 LAST CDS_LIB mstr_symbols
J 0
(-2550 2300);
PAINT ORANGE (-2550 2300);
DISPLAY INVISIBLE (-2550 2300);
FORCEPROP 1 LAST VOLTAGE 3.3V
J 0
(-2595 2257);
DISPLAY 0.340426 (-2595 2257);
PAINT SKYBLUE (-2595 2257);
DISPLAY INVISIBLE (-2595 2257);
FORCEPROP 1 LAST PATH I103
J 0
(-2505 2302);
DISPLAY 0.340426 (-2505 2302);
PAINT GREEN (-2505 2302);
DISPLAY INVISIBLE (-2505 2302);
FORCEADD PVCCIO_CPU0..1
(-3100 2300);
FORCEPROP 3 LASTPIN (-3100 2250) SIG_NAME PVCCIO_CPU0\g
J 0
(-3090 2260);
DISPLAY 0.659574 (-3090 2260);
PAINT MONO (-3090 2260);
DISPLAY INVISIBLE (-3090 2260);
FORCEPROP 1 LAST HDL_POWER PVCCIO_CPU0
J 1
(-3100 2350);
DISPLAY 0.872340 (-3100 2350);
PAINT GREEN (-3100 2350);
DISPLAY INVISIBLE (-3100 2350);
FORCEPROP 1 LAST BODY_TYPE PLUMBING
J 0
(-3145 2257);
DISPLAY 0.340426 (-3145 2257);
PAINT GREEN (-3145 2257);
DISPLAY INVISIBLE (-3145 2257);
FORCEPROP 1 LAST VOLTAGE 1.1V
J 0
(-3145 2257);
DISPLAY 0.340426 (-3145 2257);
PAINT SKYBLUE (-3145 2257);
DISPLAY INVISIBLE (-3145 2257);
FORCEPROP 2 LAST CDS_LIB mstr_symbols
J 0
(-3100 2300);
PAINT ORANGE (-3100 2300);
DISPLAY INVISIBLE (-3100 2300);
FORCEPROP 1 LAST PATH I104
J 0
(-3050 2325);
DISPLAY 0.872340 (-3050 2325);
PAINT AQUA (-3050 2325);
DISPLAY INVISIBLE (-3050 2325);
FORCEADD RES..2
(-3100 2075);
FORCEPROP 1 LAST PACK_TYPE 0402
J 0
(-2985 1900);
DISPLAY 0.617021 (-2985 1900);
PAINT SKYBLUE (-2985 1900);
FORCEPROP 1 LAST PART_NUMBER G21796-047
J 0
(-2985 1950);
DISPLAY 0.617021 (-2985 1950);
PAINT BLUE (-2985 1950);
FORCEPROP 1 LASTPIN (-3100 2175) $PN 1
J 0
(-3095 2137);
DISPLAY 0.617021 (-3095 2137);
PAINT ORANGE (-3095 2137);
FORCEPROP 1 LASTPIN (-3100 1975) $PN 2
J 0
(-3095 1985);
DISPLAY 0.617021 (-3095 1985);
PAINT ORANGE (-3095 1985);
FORCEPROP 1 LAST LOCATION R1W35
J 0
(-2980 2200);
DISPLAY 0.617021 (-2980 2200);
PAINT AQUA (-2980 2200);
FORCEPROP 1 LAST VALUE 49.9
J 0
(-2980 2150);
DISPLAY 0.617021 (-2980 2150);
PAINT SKYBLUE (-2980 2150);
FORCEPROP 1 LAST TOLERANCE 1%
J 0
(-2980 2100);
DISPLAY 0.617021 (-2980 2100);
PAINT SKYBLUE (-2980 2100);
FORCEPROP 1 LAST WATTAGE 1/16W
J 0
(-2985 2050);
DISPLAY 0.617021 (-2985 2050);
PAINT SKYBLUE (-2985 2050);
FORCEPROP 1 LAST MATERIAL EMPTY
J 0
(-2985 2000);
DISPLAY 0.617021 (-2985 2000);
PAINT RED (-2985 2000);
FORCEPROP 0 LAST CDS_SEC 1
J 0
(-3050 2250);
DISPLAY INVISIBLE (-3050 2250);
FORCEPROP 2 LAST SEC_TYPE 0402
J 0
(-3050 2300);
DISPLAY 1.021277 (-3050 2300);
PAINT ORANGE (-3050 2300);
DISPLAY INVISIBLE (-3050 2300);
FORCEPROP 2 LAST SEC 1
J 0
(-3050 2300);
DISPLAY 0.680851 (-3050 2300);
PAINT MONO (-3050 2300);
DISPLAY INVISIBLE (-3050 2300);
FORCEPROP 0 LAST ROOM SB
J 0
(-3150 2275);
DISPLAY 1.021277 (-3150 2275);
PAINT ORANGE (-3150 2275);
DISPLAY INVISIBLE (-3150 2275);
FORCEPROP 2 LAST CDS_LIB mstr_discrete
J 0
(-3100 2075);
PAINT ORANGE (-3100 2075);
DISPLAY INVISIBLE (-3100 2075);
FORCEPROP 1 LAST PATH I105
J 0
(-3050 2250);
DISPLAY 0.978723 (-3050 2250);
PAINT WHITE (-3050 2250);
DISPLAY INVISIBLE (-3050 2250);
FORCEPROP 2 LAST CDS_LOCATION R1W35
J 0
(-3055 2200);
DISPLAY 0.617021 (-3055 2200);
PAINT AQUA (-3055 2200);
DISPLAY INVISIBLE (-3055 2200);
FORCEADD 374R2F-1-GP..1
(-2550 2075);
FORCEPROP 2 LAST PACK_SIZE 0402
J 0
(-2500 1950);
DISPLAY 0.638298 (-2500 1950);
PAINT GREEN (-2500 1950);
FORCEPROP 1 LAST LOCATION R1U43
J 0
(-2500 2205);
DISPLAY 0.617021 (-2500 2205);
PAINT GREEN (-2500 2205);
FORCEPROP 1 LAST VALUE 374R2F-1-GP
J 0
(-2500 2150);
DISPLAY 0.617021 (-2500 2150);
PAINT GREEN (-2500 2150);
FORCEPROP 2 LAST ATTRIBUTE 374 OHM
J 0
(-2500 2100);
DISPLAY 0.638298 (-2500 2100);
PAINT GREEN (-2500 2100);
FORCEPROP 2 LAST TOLERANCE 1%
J 0
(-2500 2050);
DISPLAY 0.638298 (-2500 2050);
PAINT GREEN (-2500 2050);
FORCEPROP 2 LAST RATED 1/16W
J 0
(-2500 2000);
DISPLAY 0.638298 (-2500 2000);
PAINT GREEN (-2500 2000);
FORCEPROP 1 LAST PATH I106
J 0
(-2550 2075);
DISPLAY 0.617021 (-2550 2075);
PAINT GREEN (-2550 2075);
DISPLAY INVISIBLE (-2550 2075);
FORCEPROP 1 LAST CDS_LMAN_SYM_OUTLINE -50,75,50,-75
J 0
(-2550 2075);
DISPLAY 0.468085 (-2550 2075);
PAINT GREEN (-2550 2075);
DISPLAY INVISIBLE (-2550 2075);
FORCEPROP 2 LAST CDS_LIB w_hdl
J 0
(-2550 2075);
DISPLAY INVISIBLE (-2550 2075);
FORCEPROP 1 LAST PART_NUMBER 64.37405.6DL
J 0
(-2550 2075);
DISPLAY 0.617021 (-2550 2075);
PAINT GREEN (-2550 2075);
DISPLAY INVISIBLE (-2550 2075);
FORCEPROP 1 LAST PACK_TYPE SMD-RG
J 0
(-2550 2075);
DISPLAY 0.617021 (-2550 2075);
PAINT GREEN (-2550 2075);
DISPLAY INVISIBLE (-2550 2075);
FORCEADD OFFPAGE..2
(-1400 4075);
FORCEPROP 2 LAST $XR0 152 
J 0
(-1211 4075);
DISPLAY 0.638298 (-1211 4075);
PAINT MONO (-1211 4075);
FORCEPROP 2 LAST CDS_LIB mstr_standard
J 0
(-1400 4075);
PAINT ORANGE (-1400 4075);
DISPLAY INVISIBLE (-1400 4075);
FORCEPROP 2 LAST PATH I11
J 0
(-1225 4150);
DISPLAY 1.021277 (-1225 4150);
PAINT ORANGE (-1225 4150);
DISPLAY INVISIBLE (-1225 4150);
FORCEPROP 1 LAST OFFPAGE TRUE
J 0
(-1075 3950);
DISPLAY 0.872340 (-1075 3950);
PAINT GREEN (-1075 3950);
DISPLAY INVISIBLE (-1075 3950);
FORCEPROP 1 LAST COMMENT_BODY TRUE
J 0
(-1445 3980);
DISPLAY 0.872340 (-1445 3980);
PAINT GREEN (-1445 3980);
DISPLAY INVISIBLE (-1445 3980);
FORCEADD OFFPAGE..2
(-1400 3900);
FORCEPROP 2 LAST $XR0 152 
J 0
(-1211 3900);
DISPLAY 0.638298 (-1211 3900);
PAINT MONO (-1211 3900);
FORCEPROP 2 LAST CDS_LIB mstr_standard
J 0
(-1400 3900);
PAINT ORANGE (-1400 3900);
DISPLAY INVISIBLE (-1400 3900);
FORCEPROP 2 LAST PATH I12
J 0
(-1225 3975);
DISPLAY 1.021277 (-1225 3975);
PAINT ORANGE (-1225 3975);
DISPLAY INVISIBLE (-1225 3975);
FORCEPROP 1 LAST OFFPAGE TRUE
J 0
(-1075 3775);
DISPLAY 0.872340 (-1075 3775);
PAINT GREEN (-1075 3775);
DISPLAY INVISIBLE (-1075 3775);
FORCEPROP 1 LAST COMMENT_BODY TRUE
J 0
(-1445 3805);
DISPLAY 0.872340 (-1445 3805);
PAINT GREEN (-1445 3805);
DISPLAY INVISIBLE (-1445 3805);
FORCEADD OFFPAGE..2
(-1400 3725);
FORCEPROP 2 LAST $XR0 152 
J 0
(-1211 3725);
DISPLAY 0.638298 (-1211 3725);
PAINT MONO (-1211 3725);
FORCEPROP 2 LAST CDS_LIB mstr_standard
J 0
(-1400 3725);
PAINT ORANGE (-1400 3725);
DISPLAY INVISIBLE (-1400 3725);
FORCEPROP 2 LAST PATH I13
J 0
(-1225 3800);
DISPLAY 1.021277 (-1225 3800);
PAINT ORANGE (-1225 3800);
DISPLAY INVISIBLE (-1225 3800);
FORCEPROP 1 LAST OFFPAGE TRUE
J 0
(-1075 3600);
DISPLAY 0.872340 (-1075 3600);
PAINT GREEN (-1075 3600);
DISPLAY INVISIBLE (-1075 3600);
FORCEPROP 1 LAST COMMENT_BODY TRUE
J 0
(-1445 3630);
DISPLAY 0.872340 (-1445 3630);
PAINT GREEN (-1445 3630);
DISPLAY INVISIBLE (-1445 3630);
FORCEADD RES..1
(-2400 4075);
FORCEPROP 1 LAST PART_NUMBER G21796-074
J 0
(-2175 4025);
DISPLAY 0.617021 (-2175 4025);
PAINT BLUE (-2175 4025);
FORCEPROP 1 LAST LOCATION R9G31
J 0
(-2450 4125);
DISPLAY 0.617021 (-2450 4125);
PAINT AQUA (-2450 4125);
FORCEPROP 1 LAST TOLERANCE 1%
J 0
(-2425 4025);
DISPLAY 0.617021 (-2425 4025);
PAINT SKYBLUE (-2425 4025);
FORCEPROP 1 LAST VALUE 33.2
J 2
(-2450 4025);
DISPLAY 0.617021 (-2450 4025);
PAINT SKYBLUE (-2450 4025);
FORCEPROP 1 LAST WATTAGE 1/16W
J 2
(-2200 4025);
DISPLAY 0.617021 (-2200 4025);
PAINT SKYBLUE (-2200 4025);
FORCEPROP 1 LAST PACK_TYPE 0402
J 0
(-1950 4025);
DISPLAY 0.617021 (-1950 4025);
PAINT SKYBLUE (-1950 4025);
FORCEPROP 1 LAST MATERIAL CHIP
J 0
(-1850 4025);
DISPLAY 0.617021 (-1850 4025);
PAINT SKYBLUE (-1850 4025);
FORCEPROP 1 LASTPIN (-2500 4075) $PN 1
J 0
(-2488 4087);
DISPLAY 0.617021 (-2488 4087);
PAINT ORANGE (-2488 4087);
FORCEPROP 1 LASTPIN (-2300 4075) $PN 2
J 0
(-2338 4087);
DISPLAY 0.617021 (-2338 4087);
PAINT ORANGE (-2338 4087);
FORCEPROP 2 LAST CDS_LIB mstr_discrete
J 0
(-2400 4075);
PAINT ORANGE (-2400 4075);
DISPLAY INVISIBLE (-2400 4075);
FORCEPROP 2 LAST ROOM PROC_SIDEBAND
J 0
(-2450 4175);
DISPLAY 1.021277 (-2450 4175);
PAINT ORANGE (-2450 4175);
DISPLAY INVISIBLE (-2450 4175);
FORCEPROP 2 LAST SEC_TYPE 0402
J 0
(-2450 4275);
DISPLAY 1.021277 (-2450 4275);
PAINT ORANGE (-2450 4275);
DISPLAY INVISIBLE (-2450 4275);
FORCEPROP 2 LAST BOM_COST PROC_SIDEBAND
J 0
(-2450 4225);
DISPLAY 1.021277 (-2450 4225);
PAINT ORANGE (-2450 4225);
DISPLAY INVISIBLE (-2450 4225);
FORCEPROP 2 LAST SEC 1
J 0
(-2450 4275);
DISPLAY 0.680851 (-2450 4275);
PAINT MONO (-2450 4275);
DISPLAY INVISIBLE (-2450 4275);
FORCEPROP 1 LAST PATH I14
J 0
(-2450 4225);
DISPLAY 0.978723 (-2450 4225);
PAINT WHITE (-2450 4225);
DISPLAY INVISIBLE (-2450 4225);
FORCEADD RES..1
(-2400 3900);
FORCEPROP 1 LAST VALUE 33.2
J 2
(-2450 3850);
DISPLAY 0.617021 (-2450 3850);
PAINT SKYBLUE (-2450 3850);
FORCEPROP 1 LAST TOLERANCE 1%
J 0
(-2425 3850);
DISPLAY 0.617021 (-2425 3850);
PAINT SKYBLUE (-2425 3850);
FORCEPROP 1 LAST MATERIAL CHIP
J 0
(-1850 3850);
DISPLAY 0.617021 (-1850 3850);
PAINT SKYBLUE (-1850 3850);
FORCEPROP 1 LAST LOCATION R1U36
J 0
(-2450 3950);
DISPLAY 0.617021 (-2450 3950);
PAINT AQUA (-2450 3950);
FORCEPROP 1 LASTPIN (-2300 3900) $PN 2
J 0
(-2338 3912);
DISPLAY 0.617021 (-2338 3912);
PAINT ORANGE (-2338 3912);
FORCEPROP 1 LASTPIN (-2500 3900) $PN 1
J 0
(-2488 3912);
DISPLAY 0.617021 (-2488 3912);
PAINT ORANGE (-2488 3912);
FORCEPROP 1 LAST PACK_TYPE 0402
J 0
(-1950 3850);
DISPLAY 0.617021 (-1950 3850);
PAINT SKYBLUE (-1950 3850);
FORCEPROP 1 LAST PART_NUMBER G21796-074
J 0
(-2175 3850);
DISPLAY 0.617021 (-2175 3850);
PAINT BLUE (-2175 3850);
FORCEPROP 1 LAST WATTAGE 1/16W
J 2
(-2200 3850);
DISPLAY 0.617021 (-2200 3850);
PAINT SKYBLUE (-2200 3850);
FORCEPROP 2 LAST CDS_LIB mstr_discrete
J 0
(-2400 3900);
PAINT ORANGE (-2400 3900);
DISPLAY INVISIBLE (-2400 3900);
FORCEPROP 2 LAST CDS_LOCATION R1U36
J 0
(-2450 3950);
DISPLAY 0.617021 (-2450 3950);
PAINT AQUA (-2450 3950);
DISPLAY INVISIBLE (-2450 3950);
FORCEPROP 2 LAST ROOM PROC_SIDEBAND
J 0
(-2450 4000);
DISPLAY 1.021277 (-2450 4000);
PAINT ORANGE (-2450 4000);
DISPLAY INVISIBLE (-2450 4000);
FORCEPROP 1 LAST PATH I15
J 0
(-2450 4050);
DISPLAY 0.978723 (-2450 4050);
PAINT WHITE (-2450 4050);
DISPLAY INVISIBLE (-2450 4050);
FORCEPROP 2 LAST BOM_COST PROC_SIDEBAND
J 0
(-2450 4050);
DISPLAY 1.021277 (-2450 4050);
PAINT ORANGE (-2450 4050);
DISPLAY INVISIBLE (-2450 4050);
FORCEPROP 2 LAST SEC_TYPE 0402
J 0
(-2450 4100);
DISPLAY 1.021277 (-2450 4100);
PAINT ORANGE (-2450 4100);
DISPLAY INVISIBLE (-2450 4100);
FORCEPROP 2 LAST SEC 1
J 0
(-2450 4100);
DISPLAY 0.680851 (-2450 4100);
PAINT MONO (-2450 4100);
DISPLAY INVISIBLE (-2450 4100);
FORCEADD RES..1
(-2400 3725);
FORCEPROP 1 LAST VALUE 33.2
J 2
(-2450 3675);
DISPLAY 0.617021 (-2450 3675);
PAINT SKYBLUE (-2450 3675);
FORCEPROP 1 LAST TOLERANCE 1%
J 0
(-2425 3675);
DISPLAY 0.617021 (-2425 3675);
PAINT SKYBLUE (-2425 3675);
FORCEPROP 1 LAST WATTAGE 1/16W
J 2
(-2200 3675);
DISPLAY 0.617021 (-2200 3675);
PAINT SKYBLUE (-2200 3675);
FORCEPROP 1 LAST PART_NUMBER G21796-074
J 0
(-2175 3675);
DISPLAY 0.617021 (-2175 3675);
PAINT BLUE (-2175 3675);
FORCEPROP 1 LAST PACK_TYPE 0402
J 0
(-1950 3675);
DISPLAY 0.617021 (-1950 3675);
PAINT SKYBLUE (-1950 3675);
FORCEPROP 1 LASTPIN (-2500 3725) $PN 1
J 0
(-2488 3737);
DISPLAY 0.617021 (-2488 3737);
PAINT ORANGE (-2488 3737);
FORCEPROP 1 LAST LOCATION R1U34
J 0
(-2450 3775);
DISPLAY 0.617021 (-2450 3775);
PAINT AQUA (-2450 3775);
FORCEPROP 1 LAST MATERIAL CHIP
J 0
(-1850 3675);
DISPLAY 0.617021 (-1850 3675);
PAINT SKYBLUE (-1850 3675);
FORCEPROP 1 LASTPIN (-2300 3725) $PN 2
J 0
(-2338 3737);
DISPLAY 0.617021 (-2338 3737);
PAINT ORANGE (-2338 3737);
FORCEPROP 2 LAST CDS_LIB mstr_discrete
J 0
(-2400 3725);
PAINT ORANGE (-2400 3725);
DISPLAY INVISIBLE (-2400 3725);
FORCEPROP 2 LAST CDS_LOCATION R1U34
J 0
(-2450 3775);
DISPLAY 0.617021 (-2450 3775);
PAINT AQUA (-2450 3775);
DISPLAY INVISIBLE (-2450 3775);
FORCEPROP 2 LAST ROOM PROC_TRANSLATORS
J 0
(-2450 3825);
DISPLAY 1.021277 (-2450 3825);
PAINT ORANGE (-2450 3825);
DISPLAY INVISIBLE (-2450 3825);
FORCEPROP 1 LAST PATH I16
J 0
(-2450 3875);
DISPLAY 0.978723 (-2450 3875);
PAINT WHITE (-2450 3875);
DISPLAY INVISIBLE (-2450 3875);
FORCEPROP 2 LAST SEC_TYPE 0402
J 0
(-2450 3925);
DISPLAY 1.021277 (-2450 3925);
PAINT ORANGE (-2450 3925);
DISPLAY INVISIBLE (-2450 3925);
FORCEPROP 2 LAST BOM_COST PROC_SIDEBAND
J 0
(-2450 3875);
DISPLAY 1.021277 (-2450 3875);
PAINT ORANGE (-2450 3875);
DISPLAY INVISIBLE (-2450 3875);
FORCEPROP 2 LAST SEC 1
J 0
(-2450 3925);
DISPLAY 0.680851 (-2450 3925);
PAINT MONO (-2450 3925);
DISPLAY INVISIBLE (-2450 3925);
FORCEADD GND..1
(-5900 3525);
FORCEPROP 3 LASTPIN (-5900 3575) SIG_NAME GND\g
J 0
(-5890 3585);
DISPLAY 0.659574 (-5890 3585);
PAINT MONO (-5890 3585);
DISPLAY INVISIBLE (-5890 3585);
FORCEPROP 1 LAST VOLTAGE 0.0V
J 0
(-5945 3482);
DISPLAY 0.340426 (-5945 3482);
PAINT SKYBLUE (-5945 3482);
DISPLAY INVISIBLE (-5945 3482);
FORCEPROP 2 LAST CDS_LIB mstr_symbols
J 0
(-5900 3525);
PAINT ORANGE (-5900 3525);
DISPLAY INVISIBLE (-5900 3525);
FORCEPROP 1 LAST SIZE 1B
J 0
(-5825 3475);
DISPLAY 0.872340 (-5825 3475);
PAINT AQUA (-5825 3475);
DISPLAY INVISIBLE (-5825 3475);
FORCEPROP 1 LAST PATH I17
J 0
(-5825 3525);
DISPLAY 0.872340 (-5825 3525);
PAINT AQUA (-5825 3525);
DISPLAY INVISIBLE (-5825 3525);
FORCEPROP 1 LAST BODY_TYPE PLUMBING
J 0
(-5945 3482);
DISPLAY 0.340426 (-5945 3482);
PAINT GREEN (-5945 3482);
DISPLAY INVISIBLE (-5945 3482);
FORCEPROP 1 LAST HDL_POWER GND
J 0
(-5900 3675);
DISPLAY 0.872340 (-5900 3675);
PAINT GREEN (-5900 3675);
DISPLAY INVISIBLE (-5900 3675);
FORCEADD CAP..1
(-4525 4650);
FORCEPROP 1 LAST VALUE 1.0UF
J 0
(-4475 4700);
DISPLAY 0.617021 (-4475 4700);
PAINT SKYBLUE (-4475 4700);
FORCEPROP 1 LAST LOCATION C1U19
J 0
(-4475 4750);
DISPLAY 0.617021 (-4475 4750);
PAINT AQUA (-4475 4750);
FORCEPROP 1 LAST VOLTAGE 16V
J 0
(-4475 4650);
DISPLAY 0.617021 (-4475 4650);
PAINT SKYBLUE (-4475 4650);
FORCEPROP 1 LASTPIN (-4525 4750) $PN 1
J 0
(-4515 4730);
DISPLAY 0.617021 (-4515 4730);
PAINT ORANGE (-4515 4730);
FORCEPROP 1 LAST PACK_TYPE 0402
J 0
(-4475 4450);
DISPLAY 0.617021 (-4475 4450);
PAINT SKYBLUE (-4475 4450);
FORCEPROP 1 LAST MATERIAL X6S
J 0
(-4475 4550);
DISPLAY 0.617021 (-4475 4550);
PAINT SKYBLUE (-4475 4550);
FORCEPROP 1 LASTPIN (-4525 4550) $PN 2
J 0
(-4515 4530);
DISPLAY 0.617021 (-4515 4530);
PAINT ORANGE (-4515 4530);
FORCEPROP 1 LAST PART_NUMBER D97712-011
J 0
(-4475 4500);
DISPLAY 0.617021 (-4475 4500);
PAINT BLUE (-4475 4500);
FORCEPROP 1 LAST TOLERANCE 10%
J 0
(-4475 4600);
DISPLAY 0.617021 (-4475 4600);
PAINT SKYBLUE (-4475 4600);
FORCEPROP 2 LAST SEC_TYPE 0402
J 0
(-4475 4850);
DISPLAY 1.021277 (-4475 4850);
PAINT ORANGE (-4475 4850);
DISPLAY INVISIBLE (-4475 4850);
FORCEPROP 2 LAST BOM_COST PROC_SIDEBAND
J 0
(-4475 4850);
DISPLAY 1.021277 (-4475 4850);
PAINT ORANGE (-4475 4850);
DISPLAY INVISIBLE (-4475 4850);
FORCEPROP 2 LAST SEC 1
J 0
(-4475 4850);
PAINT MONO (-4475 4850);
DISPLAY INVISIBLE (-4475 4850);
FORCEPROP 2 LAST CDS_LIB mstr_discrete
J 0
(-4525 4650);
PAINT ORANGE (-4525 4650);
DISPLAY INVISIBLE (-4525 4650);
FORCEPROP 2 LAST CDS_LOCATION C1U19
J 0
(-4475 4750);
DISPLAY 0.617021 (-4475 4750);
PAINT AQUA (-4475 4750);
DISPLAY INVISIBLE (-4475 4750);
FORCEPROP 1 LAST PATH I18
J 0
(-4475 4800);
DISPLAY 0.978723 (-4475 4800);
PAINT WHITE (-4475 4800);
DISPLAY INVISIBLE (-4475 4800);
FORCEPROP 2 LAST ROOM PROC_SIDEBAND
J 0
(-4475 4800);
DISPLAY 1.021277 (-4475 4800);
PAINT ORANGE (-4475 4800);
DISPLAY INVISIBLE (-4475 4800);
FORCEADD RES..1
(-4350 4200);
FORCEPROP 1 LAST MATERIAL CHIP
J 0
(-4050 4100);
DISPLAY 0.617021 (-4050 4100);
PAINT SKYBLUE (-4050 4100);
FORCEPROP 1 LASTPIN (-4450 4200) $PN 1
J 0
(-4438 4212);
DISPLAY 0.617021 (-4438 4212);
PAINT ORANGE (-4438 4212);
FORCEPROP 1 LASTPIN (-4250 4200) $PN 2
J 0
(-4288 4212);
DISPLAY 0.617021 (-4288 4212);
PAINT ORANGE (-4288 4212);
FORCEPROP 1 LAST PART_NUMBER G21796-026
J 0
(-4125 4150);
DISPLAY 0.617021 (-4125 4150);
PAINT BLUE (-4125 4150);
FORCEPROP 1 LAST PACK_TYPE 0402
J 0
(-4275 4150);
DISPLAY 0.617021 (-4275 4150);
PAINT SKYBLUE (-4275 4150);
FORCEPROP 1 LAST WATTAGE 1/16W
J 2
(-4300 4150);
DISPLAY 0.617021 (-4300 4150);
PAINT SKYBLUE (-4300 4150);
FORCEPROP 1 LAST TOLERANCE 1%
J 0
(-4500 4150);
DISPLAY 0.617021 (-4500 4150);
PAINT SKYBLUE (-4500 4150);
FORCEPROP 1 LAST LOCATION R1U30
J 0
(-4400 4250);
DISPLAY 0.617021 (-4400 4250);
PAINT AQUA (-4400 4250);
FORCEPROP 1 LAST VALUE 1.00K
J 2
(-4550 4150);
DISPLAY 0.617021 (-4550 4150);
PAINT SKYBLUE (-4550 4150);
FORCEPROP 2 LAST CDS_LIB mstr_discrete
J 0
(-4350 4200);
PAINT ORANGE (-4350 4200);
DISPLAY INVISIBLE (-4350 4200);
FORCEPROP 2 LAST SEC 1
J 0
(-4400 4400);
DISPLAY 0.680851 (-4400 4400);
PAINT MONO (-4400 4400);
DISPLAY INVISIBLE (-4400 4400);
FORCEPROP 2 LAST SEC_TYPE 0402
J 0
(-4400 4400);
DISPLAY 1.021277 (-4400 4400);
PAINT ORANGE (-4400 4400);
DISPLAY INVISIBLE (-4400 4400);
FORCEPROP 2 LAST BOM_COST PROC_SIDEBAND
J 0
(-4375 4325);
DISPLAY 1.021277 (-4375 4325);
PAINT ORANGE (-4375 4325);
DISPLAY INVISIBLE (-4375 4325);
FORCEPROP 1 LAST PATH I2
J 0
(-4400 4350);
DISPLAY 0.978723 (-4400 4350);
PAINT WHITE (-4400 4350);
DISPLAY INVISIBLE (-4400 4350);
FORCEPROP 2 LAST CDS_LOCATION R1U30
J 0
(-4400 4250);
DISPLAY 0.617021 (-4400 4250);
PAINT AQUA (-4400 4250);
DISPLAY INVISIBLE (-4400 4250);
FORCEPROP 2 LAST ROOM PROC_TRANSLATORS
J 0
(-4375 4275);
DISPLAY 1.021277 (-4375 4275);
PAINT ORANGE (-4375 4275);
DISPLAY INVISIBLE (-4375 4275);
FORCEADD GND..1
(-4525 4450);
FORCEPROP 3 LASTPIN (-4525 4500) SIG_NAME GND\g
J 0
(-4515 4510);
DISPLAY 0.659574 (-4515 4510);
PAINT MONO (-4515 4510);
DISPLAY INVISIBLE (-4515 4510);
FORCEPROP 1 LAST SIZE 1B
J 0
(-4450 4400);
DISPLAY 0.872340 (-4450 4400);
PAINT AQUA (-4450 4400);
DISPLAY INVISIBLE (-4450 4400);
FORCEPROP 1 LAST PATH I20
J 0
(-4450 4450);
DISPLAY 0.872340 (-4450 4450);
PAINT AQUA (-4450 4450);
DISPLAY INVISIBLE (-4450 4450);
FORCEPROP 2 LAST CDS_LIB mstr_symbols
J 0
(-4525 4450);
PAINT ORANGE (-4525 4450);
DISPLAY INVISIBLE (-4525 4450);
FORCEPROP 1 LAST VOLTAGE 0.0V
J 0
(-4570 4407);
DISPLAY 0.340426 (-4570 4407);
PAINT SKYBLUE (-4570 4407);
DISPLAY INVISIBLE (-4570 4407);
FORCEPROP 1 LAST BODY_TYPE PLUMBING
J 0
(-4570 4407);
DISPLAY 0.340426 (-4570 4407);
PAINT GREEN (-4570 4407);
DISPLAY INVISIBLE (-4570 4407);
FORCEPROP 1 LAST HDL_POWER GND
J 0
(-4525 4600);
DISPLAY 0.872340 (-4525 4600);
PAINT GREEN (-4525 4600);
DISPLAY INVISIBLE (-4525 4600);
FORCEADD OFFPAGE..1
(-8525 4225);
FORCEPROP 2 LAST $XR2 21 
J 0
(-8956 4225);
DISPLAY 0.638298 (-8956 4225);
PAINT MONO (-8956 4225);
FORCEPROP 2 LAST $XR1 95 
J 0
(-8866 4225);
DISPLAY 0.638298 (-8866 4225);
PAINT MONO (-8866 4225);
FORCEPROP 2 LAST $XR0 94 
J 0
(-8776 4225);
DISPLAY 0.638298 (-8776 4225);
PAINT MONO (-8776 4225);
FORCEPROP 2 LAST CDS_LIB mstr_standard
J 0
(-8525 4225);
PAINT ORANGE (-8525 4225);
DISPLAY INVISIBLE (-8525 4225);
FORCEPROP 2 LAST PATH I21
J 0
(-8475 4300);
DISPLAY 1.021277 (-8475 4300);
PAINT ORANGE (-8475 4300);
DISPLAY INVISIBLE (-8475 4300);
FORCEPROP 1 LAST OFFPAGE TRUE
J 0
(-8200 4100);
DISPLAY 0.872340 (-8200 4100);
PAINT GREEN (-8200 4100);
DISPLAY INVISIBLE (-8200 4100);
FORCEPROP 1 LAST COMMENT_BODY TRUE
J 0
(-8400 4125);
DISPLAY 0.872340 (-8400 4125);
PAINT GREEN (-8400 4125);
DISPLAY INVISIBLE (-8400 4125);
FORCEADD OFFPAGE..1
(-8525 4050);
FORCEPROP 2 LAST $XR2 21 
J 0
(-8956 4050);
DISPLAY 0.638298 (-8956 4050);
PAINT MONO (-8956 4050);
FORCEPROP 2 LAST $XR1 95 
J 0
(-8866 4050);
DISPLAY 0.638298 (-8866 4050);
PAINT MONO (-8866 4050);
FORCEPROP 2 LAST $XR0 94 
J 0
(-8776 4050);
DISPLAY 0.638298 (-8776 4050);
PAINT MONO (-8776 4050);
FORCEPROP 2 LAST PATH I22
J 0
(-8475 4125);
DISPLAY 1.021277 (-8475 4125);
PAINT ORANGE (-8475 4125);
DISPLAY INVISIBLE (-8475 4125);
FORCEPROP 2 LAST CDS_LIB mstr_standard
J 0
(-8525 4050);
PAINT ORANGE (-8525 4050);
DISPLAY INVISIBLE (-8525 4050);
FORCEPROP 1 LAST OFFPAGE TRUE
J 0
(-8200 3925);
DISPLAY 0.872340 (-8200 3925);
PAINT GREEN (-8200 3925);
DISPLAY INVISIBLE (-8200 3925);
FORCEPROP 1 LAST COMMENT_BODY TRUE
J 0
(-8400 3950);
DISPLAY 0.872340 (-8400 3950);
PAINT GREEN (-8400 3950);
DISPLAY INVISIBLE (-8400 3950);
FORCEADD OFFPAGE..1
(-8525 3900);
FORCEPROP 2 LAST $XR2 95 
J 0
(-8956 3900);
DISPLAY 0.638298 (-8956 3900);
PAINT MONO (-8956 3900);
FORCEPROP 2 LAST $XR1 94 
J 0
(-8866 3900);
DISPLAY 0.638298 (-8866 3900);
PAINT MONO (-8866 3900);
FORCEPROP 2 LAST $XR0 55 
J 0
(-8776 3900);
DISPLAY 0.638298 (-8776 3900);
PAINT MONO (-8776 3900);
FORCEPROP 2 LAST PATH I23
J 0
(-8475 3975);
DISPLAY 1.021277 (-8475 3975);
PAINT ORANGE (-8475 3975);
DISPLAY INVISIBLE (-8475 3975);
FORCEPROP 2 LAST CDS_LIB mstr_standard
J 0
(-8525 3900);
PAINT ORANGE (-8525 3900);
DISPLAY INVISIBLE (-8525 3900);
FORCEPROP 1 LAST OFFPAGE TRUE
J 0
(-8200 3775);
DISPLAY 0.872340 (-8200 3775);
PAINT GREEN (-8200 3775);
DISPLAY INVISIBLE (-8200 3775);
FORCEPROP 1 LAST COMMENT_BODY TRUE
J 0
(-8400 3800);
DISPLAY 0.872340 (-8400 3800);
PAINT GREEN (-8400 3800);
DISPLAY INVISIBLE (-8400 3800);
FORCEADD OFFPAGE..1
(-8525 3750);
FORCEPROP 2 LAST $XR2 95 
J 0
(-8956 3750);
DISPLAY 0.638298 (-8956 3750);
PAINT MONO (-8956 3750);
FORCEPROP 2 LAST $XR1 94 
J 0
(-8866 3750);
DISPLAY 0.638298 (-8866 3750);
PAINT MONO (-8866 3750);
FORCEPROP 2 LAST $XR0 55 
J 0
(-8776 3750);
DISPLAY 0.638298 (-8776 3750);
PAINT MONO (-8776 3750);
FORCEPROP 2 LAST PATH I24
J 0
(-8475 3825);
DISPLAY 1.021277 (-8475 3825);
PAINT ORANGE (-8475 3825);
DISPLAY INVISIBLE (-8475 3825);
FORCEPROP 2 LAST CDS_LIB mstr_standard
J 0
(-8525 3750);
PAINT ORANGE (-8525 3750);
DISPLAY INVISIBLE (-8525 3750);
FORCEPROP 1 LAST OFFPAGE TRUE
J 0
(-8200 3625);
DISPLAY 0.872340 (-8200 3625);
PAINT GREEN (-8200 3625);
DISPLAY INVISIBLE (-8200 3625);
FORCEPROP 1 LAST COMMENT_BODY TRUE
J 0
(-8400 3650);
DISPLAY 0.872340 (-8400 3650);
PAINT GREEN (-8400 3650);
DISPLAY INVISIBLE (-8400 3650);
FORCEADD RES..2
(-2550 1600);
FORCEPROP 1 LAST MATERIAL CHIP
J 0
(-2510 1525);
DISPLAY 0.617021 (-2510 1525);
PAINT SKYBLUE (-2510 1525);
FORCEPROP 1 LASTPIN (-2550 1500) $PN 2
J 0
(-2545 1510);
DISPLAY 0.787234 (-2545 1510);
PAINT ORANGE (-2545 1510);
FORCEPROP 1 LAST PACK_TYPE 0402
J 0
(-2510 1425);
DISPLAY 0.617021 (-2510 1425);
PAINT SKYBLUE (-2510 1425);
FORCEPROP 1 LAST LOCATION R1U37
J 0
(-2505 1725);
DISPLAY 0.617021 (-2505 1725);
PAINT AQUA (-2505 1725);
FORCEPROP 1 LASTPIN (-2550 1700) $PN 1
J 0
(-2545 1662);
DISPLAY 0.787234 (-2545 1662);
PAINT ORANGE (-2545 1662);
FORCEPROP 1 LAST VALUE 100.0
J 0
(-2505 1675);
DISPLAY 0.617021 (-2505 1675);
PAINT SKYBLUE (-2505 1675);
FORCEPROP 1 LAST TOLERANCE 1%
J 0
(-2505 1625);
DISPLAY 0.617021 (-2505 1625);
PAINT SKYBLUE (-2505 1625);
FORCEPROP 1 LAST WATTAGE 1/16W
J 0
(-2510 1575);
DISPLAY 0.617021 (-2510 1575);
PAINT SKYBLUE (-2510 1575);
FORCEPROP 1 LAST PART_NUMBER G21796-017
J 0
(-2510 1475);
DISPLAY 0.617021 (-2510 1475);
PAINT BLUE (-2510 1475);
FORCEPROP 2 LAST SEC_TYPE 0402
J 0
(-2500 1825);
DISPLAY 1.021277 (-2500 1825);
PAINT ORANGE (-2500 1825);
DISPLAY INVISIBLE (-2500 1825);
FORCEPROP 2 LAST SEC 1
J 0
(-2500 1825);
PAINT MONO (-2500 1825);
DISPLAY INVISIBLE (-2500 1825);
FORCEPROP 2 LAST BOM_COST PROC_SIDEBAND
J 0
(-2500 1825);
DISPLAY 1.021277 (-2500 1825);
PAINT ORANGE (-2500 1825);
DISPLAY INVISIBLE (-2500 1825);
FORCEPROP 1 LAST PATH I26
J 0
(-2500 1775);
DISPLAY 0.978723 (-2500 1775);
PAINT WHITE (-2500 1775);
DISPLAY INVISIBLE (-2500 1775);
FORCEPROP 2 LAST ROOM PROC_SIDEBAND
J 0
(-2500 1775);
DISPLAY 1.021277 (-2500 1775);
PAINT ORANGE (-2500 1775);
DISPLAY INVISIBLE (-2500 1775);
FORCEPROP 2 LAST CDS_LOCATION R1U37
J 0
(-2505 1725);
DISPLAY 0.617021 (-2505 1725);
PAINT AQUA (-2505 1725);
DISPLAY INVISIBLE (-2505 1725);
FORCEPROP 2 LAST CDS_LIB mstr_discrete
J 0
(-2550 1600);
PAINT ORANGE (-2550 1600);
DISPLAY INVISIBLE (-2550 1600);
FORCEADD CAP_A..1
(-2925 1600);
FORCEPROP 1 LASTPIN (-2925 1700) $PN 1
J 0
(-2915 1680);
DISPLAY 0.787234 (-2915 1680);
PAINT ORANGE (-2915 1680);
FORCEPROP 1 LASTPIN (-2925 1500) $PN 2
J 0
(-2915 1480);
DISPLAY 0.787234 (-2915 1480);
PAINT ORANGE (-2915 1480);
FORCEPROP 1 LAST PART_NUMBER A36096-030
J 0
(-2875 1450);
DISPLAY 0.617021 (-2875 1450);
PAINT BLUE (-2875 1450);
FORCEPROP 1 LAST TOLERANCE 10%
J 0
(-2875 1550);
DISPLAY 0.617021 (-2875 1550);
PAINT SKYBLUE (-2875 1550);
FORCEPROP 1 LAST MATERIAL X7R
J 0
(-2875 1500);
DISPLAY 0.617021 (-2875 1500);
PAINT SKYBLUE (-2875 1500);
FORCEPROP 1 LAST LOCATION C1U22
J 0
(-2875 1700);
DISPLAY 0.617021 (-2875 1700);
PAINT AQUA (-2875 1700);
FORCEPROP 1 LAST PACK_TYPE 0402V
J 0
(-2875 1400);
DISPLAY 0.617021 (-2875 1400);
PAINT SKYBLUE (-2875 1400);
FORCEPROP 1 LAST VALUE 0.1UF
J 0
(-2875 1650);
DISPLAY 0.617021 (-2875 1650);
PAINT SKYBLUE (-2875 1650);
FORCEPROP 1 LAST VOLTAGE 16V
J 0
(-2875 1600);
DISPLAY 0.617021 (-2875 1600);
PAINT SKYBLUE (-2875 1600);
FORCEPROP 2 LAST SEC_TYPE 0402V
J 0
(-2875 1800);
DISPLAY 1.021277 (-2875 1800);
PAINT ORANGE (-2875 1800);
DISPLAY INVISIBLE (-2875 1800);
FORCEPROP 2 LAST SEC 1
J 0
(-2875 1800);
PAINT MONO (-2875 1800);
DISPLAY INVISIBLE (-2875 1800);
FORCEPROP 2 LAST BOM_COST PROC_SIDEBAND
J 0
(-2875 1800);
DISPLAY 1.021277 (-2875 1800);
PAINT ORANGE (-2875 1800);
DISPLAY INVISIBLE (-2875 1800);
FORCEPROP 2 LAST ROOM PROC_SIDEBAND
J 0
(-2875 1750);
DISPLAY 1.021277 (-2875 1750);
PAINT ORANGE (-2875 1750);
DISPLAY INVISIBLE (-2875 1750);
FORCEPROP 1 LAST PATH I27
J 0
(-2875 1750);
DISPLAY 0.978723 (-2875 1750);
PAINT WHITE (-2875 1750);
DISPLAY INVISIBLE (-2875 1750);
FORCEPROP 2 LAST CDS_LOCATION C1U22
J 0
(-2875 1700);
DISPLAY 0.617021 (-2875 1700);
PAINT AQUA (-2875 1700);
DISPLAY INVISIBLE (-2875 1700);
FORCEPROP 2 LAST CDS_LIB dev_discrete
J 0
(-2925 1600);
PAINT ORANGE (-2925 1600);
DISPLAY INVISIBLE (-2925 1600);
FORCEADD GND..1
(-2550 1275);
FORCEPROP 3 LASTPIN (-2550 1325) SIG_NAME GND\g
J 0
(-2540 1335);
DISPLAY 0.659574 (-2540 1335);
PAINT MONO (-2540 1335);
DISPLAY INVISIBLE (-2540 1335);
FORCEPROP 2 LAST CDS_LIB mstr_symbols
J 0
(-2550 1275);
PAINT ORANGE (-2550 1275);
DISPLAY INVISIBLE (-2550 1275);
FORCEPROP 1 LAST PATH I29
J 0
(-2475 1275);
DISPLAY 0.872340 (-2475 1275);
PAINT AQUA (-2475 1275);
DISPLAY INVISIBLE (-2475 1275);
FORCEPROP 1 LAST SIZE 1B
J 0
(-2475 1225);
DISPLAY 0.872340 (-2475 1225);
PAINT AQUA (-2475 1225);
DISPLAY INVISIBLE (-2475 1225);
FORCEPROP 1 LAST VOLTAGE 0.0V
J 0
(-2595 1232);
DISPLAY 0.340426 (-2595 1232);
PAINT SKYBLUE (-2595 1232);
DISPLAY INVISIBLE (-2595 1232);
FORCEPROP 1 LAST BODY_TYPE PLUMBING
J 0
(-2595 1232);
DISPLAY 0.340426 (-2595 1232);
PAINT GREEN (-2595 1232);
DISPLAY INVISIBLE (-2595 1232);
FORCEPROP 1 LAST HDL_POWER GND
J 0
(-2550 1425);
DISPLAY 0.872340 (-2550 1425);
PAINT GREEN (-2550 1425);
DISPLAY INVISIBLE (-2550 1425);
FORCEADD GND..1
(-3825 4125);
FORCEPROP 3 LASTPIN (-3825 4175) SIG_NAME GND\g
J 0
(-3815 4185);
DISPLAY 0.659574 (-3815 4185);
PAINT MONO (-3815 4185);
DISPLAY INVISIBLE (-3815 4185);
FORCEPROP 2 LAST CDS_LIB mstr_symbols
J 0
(-3825 4125);
PAINT ORANGE (-3825 4125);
DISPLAY INVISIBLE (-3825 4125);
FORCEPROP 1 LAST PATH I3
J 0
(-3750 4125);
DISPLAY 0.872340 (-3750 4125);
PAINT AQUA (-3750 4125);
DISPLAY INVISIBLE (-3750 4125);
FORCEPROP 1 LAST VOLTAGE 0.0V
J 0
(-3870 4082);
DISPLAY 0.340426 (-3870 4082);
PAINT SKYBLUE (-3870 4082);
DISPLAY INVISIBLE (-3870 4082);
FORCEPROP 1 LAST SIZE 1B
J 0
(-3750 4075);
DISPLAY 0.872340 (-3750 4075);
PAINT AQUA (-3750 4075);
DISPLAY INVISIBLE (-3750 4075);
FORCEPROP 1 LAST BODY_TYPE PLUMBING
J 0
(-3870 4082);
DISPLAY 0.340426 (-3870 4082);
PAINT GREEN (-3870 4082);
DISPLAY INVISIBLE (-3870 4082);
FORCEPROP 1 LAST HDL_POWER GND
J 0
(-3825 4275);
DISPLAY 0.872340 (-3825 4275);
PAINT GREEN (-3825 4275);
DISPLAY INVISIBLE (-3825 4275);
FORCEADD OFFPAGE..5
(-3475 1800);
FORCEPROP 2 LAST $XR0 152 
J 0
(-3760 1800);
DISPLAY 0.638298 (-3760 1800);
PAINT MONO (-3760 1800);
FORCEPROP 2 LAST CDS_LIB mstr_standard
J 0
(-3475 1800);
PAINT ORANGE (-3475 1800);
DISPLAY INVISIBLE (-3475 1800);
FORCEPROP 2 LAST PATH I30
J 0
(-3425 1875);
DISPLAY 1.021277 (-3425 1875);
PAINT ORANGE (-3425 1875);
DISPLAY INVISIBLE (-3425 1875);
FORCEPROP 1 LAST OFFPAGE TRUE
J 0
(-3150 1675);
DISPLAY 0.872340 (-3150 1675);
PAINT GREEN (-3150 1675);
DISPLAY INVISIBLE (-3150 1675);
FORCEPROP 1 LAST COMMENT_BODY TRUE
J 0
(-3375 1725);
DISPLAY 0.872340 (-3375 1725);
PAINT GREEN (-3375 1725);
DISPLAY INVISIBLE (-3375 1725);
FORCEADD OFFPAGE..4
(-4100 4300);
FORCEPROP 2 LAST $XR0 152 
J 0
(-3914 4300);
DISPLAY 0.638298 (-3914 4300);
PAINT MONO (-3914 4300);
FORCEPROP 2 LAST PATH I4
J 0
(-4050 4375);
DISPLAY 1.021277 (-4050 4375);
PAINT ORANGE (-4050 4375);
DISPLAY INVISIBLE (-4050 4375);
FORCEPROP 2 LAST CDS_LIB mstr_standard
J 0
(-4100 4300);
PAINT ORANGE (-4100 4300);
DISPLAY INVISIBLE (-4100 4300);
FORCEPROP 1 LAST OFFPAGE TRUE
J 0
(-3775 4175);
DISPLAY 0.872340 (-3775 4175);
PAINT GREEN (-3775 4175);
DISPLAY INVISIBLE (-3775 4175);
FORCEPROP 1 LAST COMMENT_BODY TRUE
J 0
(-4125 4200);
DISPLAY 0.872340 (-4125 4200);
PAINT GREEN (-4125 4200);
DISPLAY INVISIBLE (-4125 4200);
FORCEADD RES..1
(-6950 4225);
FORCEPROP 1 LAST VALUE 0.0
J 2
(-7050 4225);
DISPLAY 0.617021 (-7050 4225);
PAINT SKYBLUE (-7050 4225);
FORCEPROP 1 LASTPIN (-7050 4225) $PN 1
J 0
(-7038 4237);
DISPLAY 0.617021 (-7038 4237);
PAINT ORANGE (-7038 4237);
FORCEPROP 1 LAST LOCATION R9G34
J 0
(-7150 4275);
DISPLAY 0.617021 (-7150 4275);
PAINT AQUA (-7150 4275);
FORCEPROP 1 LAST TOLERANCE 5%
J 0
(-6950 4275);
DISPLAY 0.617021 (-6950 4275);
PAINT SKYBLUE (-6950 4275);
FORCEPROP 1 LASTPIN (-6850 4225) $PN 2
J 0
(-6888 4237);
DISPLAY 0.617021 (-6888 4237);
PAINT ORANGE (-6888 4237);
FORCEPROP 1 LAST PART_NUMBER G21497-005
J 0
(-7150 4175);
DISPLAY 0.617021 (-7150 4175);
PAINT BLUE (-7150 4175);
FORCEPROP 1 LAST MATERIAL CHIP
J 0
(-6875 4175);
DISPLAY 0.617021 (-6875 4175);
PAINT SKYBLUE (-6875 4175);
FORCEPROP 1 LAST WATTAGE 1/16W
J 1
(-6775 4275);
DISPLAY 0.617021 (-6775 4275);
PAINT SKYBLUE (-6775 4275);
FORCEPROP 1 LAST PACK_TYPE 0402
J 0
(-6850 4225);
DISPLAY 0.617021 (-6850 4225);
PAINT SKYBLUE (-6850 4225);
FORCEPROP 2 LAST SEC_TYPE 0402
J 0
(-7000 4425);
DISPLAY 1.021277 (-7000 4425);
PAINT ORANGE (-7000 4425);
DISPLAY INVISIBLE (-7000 4425);
FORCEPROP 2 LAST SEC 1
J 0
(-7000 4425);
DISPLAY 0.680851 (-7000 4425);
PAINT MONO (-7000 4425);
DISPLAY INVISIBLE (-7000 4425);
FORCEPROP 1 LAST PATH I45
J 0
(-7000 4375);
DISPLAY 0.978723 (-7000 4375);
PAINT WHITE (-7000 4375);
DISPLAY INVISIBLE (-7000 4375);
FORCEPROP 2 LAST CDS_LIB mstr_discrete
J 0
(-6950 4225);
PAINT ORANGE (-6950 4225);
DISPLAY INVISIBLE (-6950 4225);
FORCEADD RES..2
(-3150 4600);
FORCEPROP 1 LAST MATERIAL EMPTY
J 0
(-3110 4525);
DISPLAY 0.617021 (-3110 4525);
PAINT RED (-3110 4525);
FORCEPROP 1 LAST LOCATION R9G27
J 0
(-3105 4725);
DISPLAY 0.617021 (-3105 4725);
PAINT AQUA (-3105 4725);
FORCEPROP 1 LAST PART_NUMBER G21497-005
J 0
(-3110 4475);
DISPLAY 0.617021 (-3110 4475);
PAINT BLUE (-3110 4475);
FORCEPROP 1 LAST VALUE 0.0
J 0
(-3105 4675);
DISPLAY 0.617021 (-3105 4675);
PAINT SKYBLUE (-3105 4675);
FORCEPROP 1 LAST TOLERANCE 5%
J 0
(-3105 4625);
DISPLAY 0.617021 (-3105 4625);
PAINT SKYBLUE (-3105 4625);
FORCEPROP 1 LAST PACK_TYPE 0402
J 0
(-3110 4425);
DISPLAY 0.617021 (-3110 4425);
PAINT SKYBLUE (-3110 4425);
FORCEPROP 1 LAST WATTAGE 1/16W
J 0
(-3110 4575);
DISPLAY 0.617021 (-3110 4575);
PAINT SKYBLUE (-3110 4575);
FORCEPROP 1 LASTPIN (-3150 4700) $PN 1
J 0
(-3145 4662);
DISPLAY 0.617021 (-3145 4662);
PAINT ORANGE (-3145 4662);
FORCEPROP 1 LASTPIN (-3150 4500) $PN 2
J 0
(-3145 4510);
DISPLAY 0.617021 (-3145 4510);
PAINT ORANGE (-3145 4510);
FORCEPROP 2 LAST SEC_TYPE 0402
J 0
(-3100 4825);
DISPLAY 1.021277 (-3100 4825);
PAINT ORANGE (-3100 4825);
DISPLAY INVISIBLE (-3100 4825);
FORCEPROP 2 LAST SEC 1
J 0
(-3100 4825);
DISPLAY 0.680851 (-3100 4825);
PAINT MONO (-3100 4825);
DISPLAY INVISIBLE (-3100 4825);
FORCEPROP 1 LAST PATH I47
J 0
(-3100 4775);
DISPLAY 0.978723 (-3100 4775);
PAINT WHITE (-3100 4775);
DISPLAY INVISIBLE (-3100 4775);
FORCEPROP 2 LAST CDS_LIB mstr_discrete
J 0
(-3150 4600);
PAINT ORANGE (-3150 4600);
DISPLAY INVISIBLE (-3150 4600);
FORCEADD RES..1
(-6950 4050);
FORCEPROP 1 LASTPIN (-7050 4050) $PN 1
J 0
(-7038 4062);
DISPLAY 0.617021 (-7038 4062);
PAINT ORANGE (-7038 4062);
FORCEPROP 1 LAST VALUE 0.0
J 2
(-7050 4050);
DISPLAY 0.617021 (-7050 4050);
PAINT SKYBLUE (-7050 4050);
FORCEPROP 1 LAST LOCATION R1U58
J 0
(-7150 4100);
DISPLAY 0.617021 (-7150 4100);
PAINT AQUA (-7150 4100);
FORCEPROP 1 LAST TOLERANCE 5%
J 0
(-6950 4100);
DISPLAY 0.617021 (-6950 4100);
PAINT SKYBLUE (-6950 4100);
FORCEPROP 1 LAST PART_NUMBER G21497-005
J 0
(-7150 4000);
DISPLAY 0.617021 (-7150 4000);
PAINT BLUE (-7150 4000);
FORCEPROP 1 LASTPIN (-6850 4050) $PN 2
J 0
(-6888 4062);
DISPLAY 0.617021 (-6888 4062);
PAINT ORANGE (-6888 4062);
FORCEPROP 1 LAST MATERIAL CHIP
J 0
(-6875 4000);
DISPLAY 0.617021 (-6875 4000);
PAINT SKYBLUE (-6875 4000);
FORCEPROP 1 LAST PACK_TYPE 0402
J 0
(-6850 4050);
DISPLAY 0.617021 (-6850 4050);
PAINT SKYBLUE (-6850 4050);
FORCEPROP 1 LAST WATTAGE 1/16W
J 0
(-6850 4100);
DISPLAY 0.617021 (-6850 4100);
PAINT SKYBLUE (-6850 4100);
FORCEPROP 2 LAST SEC_TYPE 0402
J 0
(-7000 4250);
DISPLAY 1.021277 (-7000 4250);
PAINT ORANGE (-7000 4250);
DISPLAY INVISIBLE (-7000 4250);
FORCEPROP 2 LAST SEC 1
J 0
(-7000 4250);
DISPLAY 0.680851 (-7000 4250);
PAINT MONO (-7000 4250);
DISPLAY INVISIBLE (-7000 4250);
FORCEPROP 1 LAST PATH I49
J 0
(-7000 4200);
DISPLAY 0.978723 (-7000 4200);
PAINT WHITE (-7000 4200);
DISPLAY INVISIBLE (-7000 4200);
FORCEPROP 2 LAST CDS_LIB mstr_discrete
J 0
(-6950 4050);
PAINT ORANGE (-6950 4050);
DISPLAY INVISIBLE (-6950 4050);
FORCEADD P3V3..1
(-4775 4925);
FORCEPROP 3 LASTPIN (-4775 4875) SIG_NAME P3V3\g
J 0
(-4765 4885);
DISPLAY 0.659574 (-4765 4885);
PAINT MONO (-4765 4885);
DISPLAY INVISIBLE (-4765 4885);
FORCEPROP 1 LAST PATH I5
J 0
(-4730 4927);
DISPLAY 0.340426 (-4730 4927);
PAINT GREEN (-4730 4927);
DISPLAY INVISIBLE (-4730 4927);
FORCEPROP 1 LAST HDL_POWER P3V3
J 0
(-5100 4800);
DISPLAY 0.872340 (-5100 4800);
PAINT ORANGE (-5100 4800);
DISPLAY INVISIBLE (-5100 4800);
FORCEPROP 1 LAST BODY_TYPE PLUMBING
J 0
(-4820 4882);
DISPLAY 0.340426 (-4820 4882);
PAINT GREEN (-4820 4882);
DISPLAY INVISIBLE (-4820 4882);
FORCEPROP 1 LAST SIZE 1B
J 0
(-4730 4947);
DISPLAY 0.340426 (-4730 4947);
PAINT GREEN (-4730 4947);
DISPLAY INVISIBLE (-4730 4947);
FORCEPROP 2 LAST CDS_LIB mstr_symbols
J 0
(-4775 4925);
PAINT ORANGE (-4775 4925);
DISPLAY INVISIBLE (-4775 4925);
FORCEPROP 1 LAST VOLTAGE 3.3V
J 0
(-4820 4882);
DISPLAY 0.340426 (-4820 4882);
PAINT SKYBLUE (-4820 4882);
DISPLAY INVISIBLE (-4820 4882);
FORCEADD RES..2
(-7175 4525);
FORCEPROP 1 LAST LOCATION R1U56
J 0
(-7130 4650);
DISPLAY 0.617021 (-7130 4650);
PAINT AQUA (-7130 4650);
FORCEPROP 1 LAST VALUE 0.0
J 0
(-7130 4600);
DISPLAY 0.617021 (-7130 4600);
PAINT SKYBLUE (-7130 4600);
FORCEPROP 1 LAST MATERIAL EMPTY
J 0
(-7135 4450);
DISPLAY 0.617021 (-7135 4450);
PAINT RED (-7135 4450);
FORCEPROP 1 LAST WATTAGE 1/16W
J 0
(-7135 4500);
DISPLAY 0.617021 (-7135 4500);
PAINT SKYBLUE (-7135 4500);
FORCEPROP 1 LAST PACK_TYPE 0402
J 0
(-7135 4350);
DISPLAY 0.617021 (-7135 4350);
PAINT SKYBLUE (-7135 4350);
FORCEPROP 1 LASTPIN (-7175 4425) $PN 2
J 0
(-7170 4435);
DISPLAY 0.617021 (-7170 4435);
PAINT ORANGE (-7170 4435);
FORCEPROP 1 LASTPIN (-7175 4625) $PN 1
J 0
(-7170 4587);
DISPLAY 0.617021 (-7170 4587);
PAINT ORANGE (-7170 4587);
FORCEPROP 1 LAST PART_NUMBER G21497-005
J 0
(-7135 4400);
DISPLAY 0.617021 (-7135 4400);
PAINT BLUE (-7135 4400);
FORCEPROP 1 LAST TOLERANCE 5%
J 0
(-7130 4550);
DISPLAY 0.617021 (-7130 4550);
PAINT SKYBLUE (-7130 4550);
FORCEPROP 2 LAST SEC_TYPE 0402
J 0
(-7125 4750);
DISPLAY 1.021277 (-7125 4750);
PAINT ORANGE (-7125 4750);
DISPLAY INVISIBLE (-7125 4750);
FORCEPROP 2 LAST SEC 1
J 0
(-7125 4750);
DISPLAY 0.680851 (-7125 4750);
PAINT MONO (-7125 4750);
DISPLAY INVISIBLE (-7125 4750);
FORCEPROP 1 LAST PATH I50
J 0
(-7125 4700);
DISPLAY 0.978723 (-7125 4700);
PAINT WHITE (-7125 4700);
DISPLAY INVISIBLE (-7125 4700);
FORCEPROP 2 LAST CDS_LIB mstr_discrete
J 0
(-7175 4525);
PAINT ORANGE (-7175 4525);
DISPLAY INVISIBLE (-7175 4525);
FORCEADD RES..2
(-7450 4525);
FORCEPROP 1 LAST LOCATION R2U51
J 0
(-7405 4650);
DISPLAY 0.617021 (-7405 4650);
PAINT AQUA (-7405 4650);
FORCEPROP 1 LASTPIN (-7450 4625) $PN 1
J 0
(-7445 4587);
DISPLAY 0.617021 (-7445 4587);
PAINT ORANGE (-7445 4587);
FORCEPROP 1 LAST VALUE 0.0
J 0
(-7405 4600);
DISPLAY 0.617021 (-7405 4600);
PAINT SKYBLUE (-7405 4600);
FORCEPROP 1 LAST MATERIAL EMPTY
J 0
(-7410 4450);
DISPLAY 0.617021 (-7410 4450);
PAINT RED (-7410 4450);
FORCEPROP 1 LAST WATTAGE 1/16W
J 0
(-7410 4500);
DISPLAY 0.617021 (-7410 4500);
PAINT SKYBLUE (-7410 4500);
FORCEPROP 1 LAST TOLERANCE 5%
J 0
(-7405 4550);
DISPLAY 0.617021 (-7405 4550);
PAINT SKYBLUE (-7405 4550);
FORCEPROP 1 LASTPIN (-7450 4425) $PN 2
J 0
(-7445 4435);
DISPLAY 0.617021 (-7445 4435);
PAINT ORANGE (-7445 4435);
FORCEPROP 1 LAST PACK_TYPE 0402
J 0
(-7410 4350);
DISPLAY 0.617021 (-7410 4350);
PAINT SKYBLUE (-7410 4350);
FORCEPROP 1 LAST PART_NUMBER G21497-005
J 0
(-7410 4400);
DISPLAY 0.617021 (-7410 4400);
PAINT BLUE (-7410 4400);
FORCEPROP 1 LAST PATH I51
J 0
(-7400 4700);
DISPLAY 0.978723 (-7400 4700);
PAINT WHITE (-7400 4700);
DISPLAY INVISIBLE (-7400 4700);
FORCEPROP 2 LAST SEC 1
J 0
(-7400 4750);
DISPLAY 0.680851 (-7400 4750);
PAINT MONO (-7400 4750);
DISPLAY INVISIBLE (-7400 4750);
FORCEPROP 2 LAST SEC_TYPE 0402
J 0
(-7400 4750);
DISPLAY 1.021277 (-7400 4750);
PAINT ORANGE (-7400 4750);
DISPLAY INVISIBLE (-7400 4750);
FORCEPROP 2 LAST CDS_LIB mstr_discrete
J 0
(-7450 4525);
PAINT ORANGE (-7450 4525);
DISPLAY INVISIBLE (-7450 4525);
FORCEADD PVCCIO_CPU0..1
(-7925 4950);
FORCEPROP 3 LASTPIN (-7925 4900) SIG_NAME PVCCIO_CPU0\g
J 0
(-7915 4910);
DISPLAY 0.659574 (-7915 4910);
PAINT MONO (-7915 4910);
DISPLAY INVISIBLE (-7915 4910);
FORCEPROP 2 LAST CDS_LIB mstr_symbols
J 0
(-7925 4950);
PAINT ORANGE (-7925 4950);
DISPLAY INVISIBLE (-7925 4950);
FORCEPROP 1 LAST PATH I52
J 0
(-7875 4975);
DISPLAY 0.872340 (-7875 4975);
PAINT AQUA (-7875 4975);
DISPLAY INVISIBLE (-7875 4975);
FORCEPROP 1 LAST VOLTAGE 1.1V
J 0
(-7970 4907);
DISPLAY 0.340426 (-7970 4907);
PAINT SKYBLUE (-7970 4907);
DISPLAY INVISIBLE (-7970 4907);
FORCEPROP 1 LAST BODY_TYPE PLUMBING
J 0
(-7970 4907);
DISPLAY 0.340426 (-7970 4907);
PAINT GREEN (-7970 4907);
DISPLAY INVISIBLE (-7970 4907);
FORCEPROP 1 LAST HDL_POWER PVCCIO_CPU0
J 1
(-7925 5000);
DISPLAY 0.872340 (-7925 5000);
PAINT GREEN (-7925 5000);
DISPLAY INVISIBLE (-7925 5000);
FORCEADD RES..2
(-7875 4650);
FORCEPROP 1 LAST WATTAGE 1/16W
J 0
(-7835 4625);
DISPLAY 0.617021 (-7835 4625);
PAINT SKYBLUE (-7835 4625);
FORCEPROP 1 LAST TOLERANCE 1%
J 0
(-7830 4675);
DISPLAY 0.617021 (-7830 4675);
PAINT SKYBLUE (-7830 4675);
FORCEPROP 1 LAST LOCATION R2U40
J 0
(-7830 4775);
DISPLAY 0.617021 (-7830 4775);
PAINT AQUA (-7830 4775);
FORCEPROP 1 LAST VALUE 150.0
J 0
(-7830 4725);
DISPLAY 0.617021 (-7830 4725);
PAINT SKYBLUE (-7830 4725);
FORCEPROP 1 LASTPIN (-7875 4750) $PN 1
J 0
(-7870 4712);
DISPLAY 0.617021 (-7870 4712);
PAINT ORANGE (-7870 4712);
FORCEPROP 1 LAST PACK_TYPE 0402
J 0
(-7835 4475);
DISPLAY 0.617021 (-7835 4475);
PAINT SKYBLUE (-7835 4475);
FORCEPROP 1 LAST MATERIAL CHIP
J 0
(-7835 4575);
DISPLAY 0.617021 (-7835 4575);
PAINT SKYBLUE (-7835 4575);
FORCEPROP 1 LASTPIN (-7875 4550) $PN 2
J 0
(-7870 4560);
DISPLAY 0.617021 (-7870 4560);
PAINT ORANGE (-7870 4560);
FORCEPROP 1 LAST PART_NUMBER G21796-009
J 0
(-7835 4525);
DISPLAY 0.617021 (-7835 4525);
PAINT BLUE (-7835 4525);
FORCEPROP 2 LAST SEC 1
J 0
(-7825 4875);
DISPLAY 0.680851 (-7825 4875);
PAINT MONO (-7825 4875);
DISPLAY INVISIBLE (-7825 4875);
FORCEPROP 2 LAST SEC_TYPE 0402
J 0
(-7825 4875);
DISPLAY 1.021277 (-7825 4875);
PAINT ORANGE (-7825 4875);
DISPLAY INVISIBLE (-7825 4875);
FORCEPROP 1 LAST PATH I53
J 0
(-7825 4825);
DISPLAY 0.978723 (-7825 4825);
PAINT WHITE (-7825 4825);
DISPLAY INVISIBLE (-7825 4825);
FORCEPROP 2 LAST CDS_LOCATION R2U40
J 0
(-7830 4775);
DISPLAY 0.617021 (-7830 4775);
PAINT AQUA (-7830 4775);
DISPLAY INVISIBLE (-7830 4775);
FORCEPROP 2 LAST CDS_LIB mstr_discrete
J 0
(-7875 4650);
PAINT MONO (-7875 4650);
DISPLAY INVISIBLE (-7875 4650);
FORCEPROP 2 LAST BOM_COST PROC_SIDEBAND
J 0
(-7875 4650);
PAINT MONO (-7875 4650);
DISPLAY INVISIBLE (-7875 4650);
FORCEPROP 2 LAST ROOM PROC_SIDEBAND
J 0
(-7850 4425);
PAINT ORANGE (-7850 4425);
DISPLAY INVISIBLE (-7850 4425);
FORCEADD RES..2
R 2
(-7975 4650);
FORCEPROP 1 LASTPIN (-7975 4750) $PN 1
J 2
(-7980 4712);
DISPLAY 0.617021 (-7980 4712);
PAINT ORANGE (-7980 4712);
FORCEPROP 1 LAST LOCATION R2U41
J 2
(-7995 4775);
DISPLAY 0.617021 (-7995 4775);
PAINT AQUA (-7995 4775);
FORCEPROP 1 LAST VALUE 150.0
J 2
(-8020 4725);
DISPLAY 0.617021 (-8020 4725);
PAINT SKYBLUE (-8020 4725);
FORCEPROP 1 LAST WATTAGE 1/16W
J 2
(-8015 4625);
DISPLAY 0.617021 (-8015 4625);
PAINT SKYBLUE (-8015 4625);
FORCEPROP 1 LAST PACK_TYPE 0402
J 2
(-8015 4475);
DISPLAY 0.617021 (-8015 4475);
PAINT SKYBLUE (-8015 4475);
FORCEPROP 1 LASTPIN (-7975 4550) $PN 2
J 2
(-7980 4560);
DISPLAY 0.617021 (-7980 4560);
PAINT ORANGE (-7980 4560);
FORCEPROP 1 LAST MATERIAL CHIP
J 2
(-8015 4575);
DISPLAY 0.617021 (-8015 4575);
PAINT SKYBLUE (-8015 4575);
FORCEPROP 1 LAST PART_NUMBER G21796-009
J 2
(-8040 4525);
DISPLAY 0.617021 (-8040 4525);
PAINT BLUE (-8040 4525);
FORCEPROP 1 LAST TOLERANCE 1%
J 2
(-8020 4675);
DISPLAY 0.617021 (-8020 4675);
PAINT SKYBLUE (-8020 4675);
FORCEPROP 2 LAST SEC 1
J 0
(-8025 4875);
DISPLAY 0.680851 (-8025 4875);
PAINT MONO (-8025 4875);
DISPLAY INVISIBLE (-8025 4875);
FORCEPROP 2 LAST SEC_TYPE 0402
J 0
(-8025 4875);
DISPLAY 1.021277 (-8025 4875);
PAINT ORANGE (-8025 4875);
DISPLAY INVISIBLE (-8025 4875);
FORCEPROP 1 LAST PATH I54
J 2
(-8025 4825);
DISPLAY 0.978723 (-8025 4825);
PAINT WHITE (-8025 4825);
DISPLAY INVISIBLE (-8025 4825);
FORCEPROP 2 LAST CDS_LOCATION R2U41
J 2
(-7995 4775);
DISPLAY 0.617021 (-7995 4775);
PAINT AQUA (-7995 4775);
DISPLAY INVISIBLE (-7995 4775);
FORCEPROP 2 LAST CDS_LIB mstr_discrete
J 0
(-7975 4650);
PAINT MONO (-7975 4650);
DISPLAY INVISIBLE (-7975 4650);
FORCEPROP 2 LAST BOM_COST PROC_SIDEBAND
J 2
(-7975 4650);
PAINT MONO (-7975 4650);
DISPLAY INVISIBLE (-7975 4650);
FORCEPROP 2 LAST ROOM PROC_SIDEBAND
J 2
(-8000 4425);
PAINT ORANGE (-8000 4425);
DISPLAY INVISIBLE (-8000 4425);
FORCEADD PVCCIO_CPU1..1
(-8375 4950);
FORCEPROP 3 LASTPIN (-8375 4900) SIG_NAME PVCCIO_CPU1\g
J 0
(-8365 4910);
DISPLAY 0.659574 (-8365 4910);
PAINT MONO (-8365 4910);
DISPLAY INVISIBLE (-8365 4910);
FORCEPROP 1 LAST VOLTAGE 1.1V
J 0
(-8420 4907);
DISPLAY 0.340426 (-8420 4907);
PAINT SKYBLUE (-8420 4907);
DISPLAY INVISIBLE (-8420 4907);
FORCEPROP 2 LAST CDS_LIB mstr_symbols
J 0
(-8375 4950);
PAINT ORANGE (-8375 4950);
DISPLAY INVISIBLE (-8375 4950);
FORCEPROP 1 LAST PATH I55
J 0
(-8325 4975);
DISPLAY 0.872340 (-8325 4975);
PAINT AQUA (-8325 4975);
DISPLAY INVISIBLE (-8325 4975);
FORCEPROP 1 LAST BODY_TYPE PLUMBING
J 0
(-8420 4907);
DISPLAY 0.340426 (-8420 4907);
PAINT GREEN (-8420 4907);
DISPLAY INVISIBLE (-8420 4907);
FORCEPROP 1 LAST HDL_POWER PVCCIO_CPU1
J 1
(-8375 5000);
DISPLAY 0.872340 (-8375 5000);
PAINT GREEN (-8375 5000);
DISPLAY INVISIBLE (-8375 5000);
FORCEADD RES..2
(-8325 4650);
FORCEPROP 1 LAST LOCATION R1U41
J 0
(-8280 4775);
DISPLAY 0.617021 (-8280 4775);
PAINT AQUA (-8280 4775);
FORCEPROP 1 LAST PACK_TYPE 0402
J 0
(-8285 4475);
DISPLAY 0.617021 (-8285 4475);
PAINT SKYBLUE (-8285 4475);
FORCEPROP 1 LAST MATERIAL CHIP
J 0
(-8285 4575);
DISPLAY 0.617021 (-8285 4575);
PAINT SKYBLUE (-8285 4575);
FORCEPROP 1 LAST TOLERANCE 1%
J 0
(-8280 4675);
DISPLAY 0.617021 (-8280 4675);
PAINT SKYBLUE (-8280 4675);
FORCEPROP 1 LASTPIN (-8325 4550) $PN 2
J 0
(-8320 4560);
DISPLAY 0.617021 (-8320 4560);
PAINT ORANGE (-8320 4560);
FORCEPROP 1 LAST WATTAGE 1/16W
J 0
(-8285 4625);
DISPLAY 0.617021 (-8285 4625);
PAINT SKYBLUE (-8285 4625);
FORCEPROP 1 LAST VALUE 150.0
J 0
(-8280 4725);
DISPLAY 0.617021 (-8280 4725);
PAINT SKYBLUE (-8280 4725);
FORCEPROP 1 LASTPIN (-8325 4750) $PN 1
J 0
(-8320 4712);
DISPLAY 0.617021 (-8320 4712);
PAINT ORANGE (-8320 4712);
FORCEPROP 2 LAST SEC_TYPE 0402
J 0
(-8275 4875);
DISPLAY 1.021277 (-8275 4875);
PAINT ORANGE (-8275 4875);
DISPLAY INVISIBLE (-8275 4875);
FORCEPROP 2 LAST SEC 1
J 0
(-8275 4875);
DISPLAY 0.680851 (-8275 4875);
PAINT MONO (-8275 4875);
DISPLAY INVISIBLE (-8275 4875);
FORCEPROP 1 LAST PATH I56
J 0
(-8275 4825);
DISPLAY 0.978723 (-8275 4825);
PAINT WHITE (-8275 4825);
DISPLAY INVISIBLE (-8275 4825);
FORCEPROP 2 LAST CDS_LOCATION R1U41
J 0
(-8280 4775);
DISPLAY 0.617021 (-8280 4775);
PAINT AQUA (-8280 4775);
DISPLAY INVISIBLE (-8280 4775);
FORCEPROP 2 LAST CDS_LIB mstr_discrete
J 0
(-8325 4650);
PAINT MONO (-8325 4650);
DISPLAY INVISIBLE (-8325 4650);
FORCEPROP 2 LAST BOM_COST PROC_SIDEBAND
J 0
(-8325 4650);
PAINT MONO (-8325 4650);
DISPLAY INVISIBLE (-8325 4650);
FORCEPROP 1 LAST PART_NUMBER G21796-009
J 0
(-8285 4525);
DISPLAY 0.617021 (-8285 4525);
PAINT BLUE (-8285 4525);
DISPLAY INVISIBLE (-8285 4525);
FORCEPROP 2 LAST ROOM PROC_SIDEBAND
J 0
(-8300 4425);
PAINT ORANGE (-8300 4425);
DISPLAY INVISIBLE (-8300 4425);
FORCEADD RES..2
R 2
(-8425 4650);
FORCEPROP 1 LASTPIN (-8425 4750) $PN 1
J 2
(-8430 4712);
DISPLAY 0.617021 (-8430 4712);
PAINT ORANGE (-8430 4712);
FORCEPROP 1 LASTPIN (-8425 4550) $PN 2
J 2
(-8430 4560);
DISPLAY 0.617021 (-8430 4560);
PAINT ORANGE (-8430 4560);
FORCEPROP 1 LAST PACK_TYPE 0402
J 2
(-8465 4475);
DISPLAY 0.617021 (-8465 4475);
PAINT SKYBLUE (-8465 4475);
FORCEPROP 1 LAST PART_NUMBER G21796-009
J 2
(-8465 4525);
DISPLAY 0.617021 (-8465 4525);
PAINT BLUE (-8465 4525);
FORCEPROP 1 LAST MATERIAL CHIP
J 2
(-8465 4575);
DISPLAY 0.617021 (-8465 4575);
PAINT SKYBLUE (-8465 4575);
FORCEPROP 1 LAST LOCATION R1U35
J 2
(-8470 4775);
DISPLAY 0.617021 (-8470 4775);
PAINT AQUA (-8470 4775);
FORCEPROP 1 LAST TOLERANCE 1%
J 2
(-8470 4675);
DISPLAY 0.617021 (-8470 4675);
PAINT SKYBLUE (-8470 4675);
FORCEPROP 1 LAST WATTAGE 1/16W
J 2
(-8465 4625);
DISPLAY 0.617021 (-8465 4625);
PAINT SKYBLUE (-8465 4625);
FORCEPROP 1 LAST VALUE 150.0
J 2
(-8470 4725);
DISPLAY 0.617021 (-8470 4725);
PAINT SKYBLUE (-8470 4725);
FORCEPROP 2 LAST BOM_COST PROC_SIDEBAND
J 2
(-8425 4650);
PAINT MONO (-8425 4650);
DISPLAY INVISIBLE (-8425 4650);
FORCEPROP 2 LAST CDS_LIB mstr_discrete
J 0
(-8425 4650);
PAINT MONO (-8425 4650);
DISPLAY INVISIBLE (-8425 4650);
FORCEPROP 2 LAST SEC_TYPE 0402
J 0
(-8475 4875);
DISPLAY 1.021277 (-8475 4875);
PAINT ORANGE (-8475 4875);
DISPLAY INVISIBLE (-8475 4875);
FORCEPROP 2 LAST SEC 1
J 0
(-8475 4875);
DISPLAY 0.680851 (-8475 4875);
PAINT MONO (-8475 4875);
DISPLAY INVISIBLE (-8475 4875);
FORCEPROP 2 LAST CDS_LOCATION R1U35
J 2
(-8470 4775);
DISPLAY 0.617021 (-8470 4775);
PAINT AQUA (-8470 4775);
DISPLAY INVISIBLE (-8470 4775);
FORCEPROP 1 LAST PATH I57
J 2
(-8475 4825);
DISPLAY 0.978723 (-8475 4825);
PAINT WHITE (-8475 4825);
DISPLAY INVISIBLE (-8475 4825);
FORCEPROP 2 LAST ROOM PROC_SIDEBAND
J 2
(-8450 4425);
PAINT ORANGE (-8450 4425);
DISPLAY INVISIBLE (-8450 4425);
FORCEADD RES..2
(-7800 3250);
FORCEPROP 1 LAST LOCATION R4P17
J 0
(-7755 3375);
DISPLAY 0.617021 (-7755 3375);
PAINT AQUA (-7755 3375);
FORCEPROP 1 LASTPIN (-7800 3150) $PN 2
J 0
(-7795 3160);
DISPLAY 0.617021 (-7795 3160);
PAINT ORANGE (-7795 3160);
FORCEPROP 1 LAST MATERIAL CHIP
J 0
(-7760 3175);
DISPLAY 0.617021 (-7760 3175);
PAINT SKYBLUE (-7760 3175);
FORCEPROP 1 LAST WATTAGE 1/16W
J 0
(-7760 3225);
DISPLAY 0.617021 (-7760 3225);
PAINT SKYBLUE (-7760 3225);
FORCEPROP 1 LAST TOLERANCE 1%
J 0
(-7755 3275);
DISPLAY 0.617021 (-7755 3275);
PAINT SKYBLUE (-7755 3275);
FORCEPROP 1 LAST PART_NUMBER G21796-009
J 0
(-7760 3125);
DISPLAY 0.617021 (-7760 3125);
PAINT BLUE (-7760 3125);
FORCEPROP 1 LAST PACK_TYPE 0402
J 0
(-7760 3075);
DISPLAY 0.617021 (-7760 3075);
PAINT SKYBLUE (-7760 3075);
FORCEPROP 1 LASTPIN (-7800 3350) $PN 1
J 0
(-7795 3312);
DISPLAY 0.617021 (-7795 3312);
PAINT ORANGE (-7795 3312);
FORCEPROP 1 LAST VALUE 150.0
J 0
(-7755 3325);
DISPLAY 0.617021 (-7755 3325);
PAINT SKYBLUE (-7755 3325);
FORCEPROP 2 LAST SEC_TYPE 0402
J 0
(-7750 3475);
DISPLAY 1.021277 (-7750 3475);
PAINT ORANGE (-7750 3475);
DISPLAY INVISIBLE (-7750 3475);
FORCEPROP 2 LAST SEC 1
J 0
(-7750 3475);
DISPLAY 0.680851 (-7750 3475);
PAINT MONO (-7750 3475);
DISPLAY INVISIBLE (-7750 3475);
FORCEPROP 2 LAST CDS_LOCATION R4P17
J 0
(-7755 3375);
DISPLAY 0.617021 (-7755 3375);
PAINT AQUA (-7755 3375);
DISPLAY INVISIBLE (-7755 3375);
FORCEPROP 1 LAST PATH I58
J 0
(-7750 3425);
DISPLAY 0.978723 (-7750 3425);
PAINT WHITE (-7750 3425);
DISPLAY INVISIBLE (-7750 3425);
FORCEPROP 2 LAST CDS_LIB mstr_discrete
J 0
(-7800 3250);
PAINT MONO (-7800 3250);
DISPLAY INVISIBLE (-7800 3250);
FORCEPROP 2 LAST BOM_COST PROC_SIDEBAND
J 0
(-7800 3250);
PAINT MONO (-7800 3250);
DISPLAY INVISIBLE (-7800 3250);
FORCEPROP 2 LAST ROOM PROC_SIDEBAND
J 0
(-7775 3025);
PAINT ORANGE (-7775 3025);
DISPLAY INVISIBLE (-7775 3025);
FORCEADD RES..2
R 2
(-7900 3250);
FORCEPROP 1 LAST PART_NUMBER G21796-009
J 2
(-7915 3075);
DISPLAY 0.617021 (-7915 3075);
PAINT BLUE (-7915 3075);
FORCEPROP 1 LAST PACK_TYPE 0402
J 2
(-7940 3025);
DISPLAY 0.617021 (-7940 3025);
PAINT SKYBLUE (-7940 3025);
FORCEPROP 1 LAST WATTAGE 1/16W
J 2
(-7940 3225);
DISPLAY 0.617021 (-7940 3225);
PAINT SKYBLUE (-7940 3225);
FORCEPROP 1 LASTPIN (-7900 3150) $PN 2
J 2
(-7905 3160);
DISPLAY 0.617021 (-7905 3160);
PAINT ORANGE (-7905 3160);
FORCEPROP 1 LAST LOCATION R4P20
J 2
(-7895 3400);
DISPLAY 0.617021 (-7895 3400);
PAINT AQUA (-7895 3400);
FORCEPROP 1 LASTPIN (-7900 3350) $PN 1
J 2
(-7905 3312);
DISPLAY 0.617021 (-7905 3312);
PAINT ORANGE (-7905 3312);
FORCEPROP 1 LAST TOLERANCE 1%
J 2
(-7945 3275);
DISPLAY 0.617021 (-7945 3275);
PAINT SKYBLUE (-7945 3275);
FORCEPROP 1 LAST VALUE 150.0
J 2
(-7945 3325);
DISPLAY 0.617021 (-7945 3325);
PAINT SKYBLUE (-7945 3325);
FORCEPROP 1 LAST MATERIAL CHIP
J 2
(-7940 3175);
DISPLAY 0.617021 (-7940 3175);
PAINT SKYBLUE (-7940 3175);
FORCEPROP 2 LAST CDS_LOCATION R4P20
J 2
(-7895 3400);
DISPLAY 0.617021 (-7895 3400);
PAINT AQUA (-7895 3400);
DISPLAY INVISIBLE (-7895 3400);
FORCEPROP 2 LAST BOM_COST PROC_SIDEBAND
J 2
(-7900 3250);
PAINT MONO (-7900 3250);
DISPLAY INVISIBLE (-7900 3250);
FORCEPROP 2 LAST CDS_LIB mstr_discrete
J 0
(-7900 3250);
PAINT MONO (-7900 3250);
DISPLAY INVISIBLE (-7900 3250);
FORCEPROP 2 LAST SEC_TYPE 0402
J 0
(-7950 3475);
DISPLAY 1.021277 (-7950 3475);
PAINT ORANGE (-7950 3475);
DISPLAY INVISIBLE (-7950 3475);
FORCEPROP 2 LAST SEC 1
J 0
(-7950 3475);
DISPLAY 0.680851 (-7950 3475);
PAINT MONO (-7950 3475);
DISPLAY INVISIBLE (-7950 3475);
FORCEPROP 1 LAST PATH I59
J 2
(-7950 3425);
DISPLAY 0.978723 (-7950 3425);
PAINT WHITE (-7950 3425);
DISPLAY INVISIBLE (-7950 3425);
FORCEPROP 2 LAST ROOM PROC_SIDEBAND
J 2
(-7925 3025);
PAINT ORANGE (-7925 3025);
DISPLAY INVISIBLE (-7925 3025);
FORCEADD RES..1
(-2400 4250);
FORCEPROP 1 LASTPIN (-2300 4250) $PN 2
J 0
(-2338 4262);
DISPLAY 0.617021 (-2338 4262);
PAINT ORANGE (-2338 4262);
FORCEPROP 1 LAST PART_NUMBER G21796-074
J 0
(-2175 4200);
DISPLAY 0.617021 (-2175 4200);
PAINT BLUE (-2175 4200);
FORCEPROP 1 LAST WATTAGE 1/16W
J 2
(-2200 4200);
DISPLAY 0.617021 (-2200 4200);
PAINT SKYBLUE (-2200 4200);
FORCEPROP 1 LAST VALUE 33.2
J 2
(-2450 4200);
DISPLAY 0.617021 (-2450 4200);
PAINT SKYBLUE (-2450 4200);
FORCEPROP 1 LASTPIN (-2500 4250) $PN 1
J 0
(-2488 4262);
DISPLAY 0.617021 (-2488 4262);
PAINT ORANGE (-2488 4262);
FORCEPROP 1 LAST LOCATION R1U46
J 0
(-2450 4300);
DISPLAY 0.617021 (-2450 4300);
PAINT AQUA (-2450 4300);
FORCEPROP 1 LAST TOLERANCE 1%
J 0
(-2425 4200);
DISPLAY 0.617021 (-2425 4200);
PAINT SKYBLUE (-2425 4200);
FORCEPROP 1 LAST MATERIAL CHIP
J 0
(-1850 4200);
DISPLAY 0.617021 (-1850 4200);
PAINT SKYBLUE (-1850 4200);
FORCEPROP 1 LAST PACK_TYPE 0402
J 0
(-1950 4200);
DISPLAY 0.617021 (-1950 4200);
PAINT SKYBLUE (-1950 4200);
FORCEPROP 2 LAST CDS_LOCATION R1U46
J 0
(-2450 4300);
DISPLAY 0.617021 (-2450 4300);
PAINT AQUA (-2450 4300);
DISPLAY INVISIBLE (-2450 4300);
FORCEPROP 2 LAST CDS_LIB mstr_discrete
J 0
(-2400 4250);
PAINT ORANGE (-2400 4250);
DISPLAY INVISIBLE (-2400 4250);
FORCEPROP 2 LAST ROOM PROC_SIDEBAND
J 0
(-2450 4350);
DISPLAY 1.021277 (-2450 4350);
PAINT ORANGE (-2450 4350);
DISPLAY INVISIBLE (-2450 4350);
FORCEPROP 2 LAST SEC_TYPE 0402
J 0
(-2450 4450);
DISPLAY 1.021277 (-2450 4450);
PAINT ORANGE (-2450 4450);
DISPLAY INVISIBLE (-2450 4450);
FORCEPROP 2 LAST BOM_COST PROC_SIDEBAND
J 0
(-2450 4400);
DISPLAY 1.021277 (-2450 4400);
PAINT ORANGE (-2450 4400);
DISPLAY INVISIBLE (-2450 4400);
FORCEPROP 2 LAST SEC 1
J 0
(-2450 4450);
DISPLAY 0.680851 (-2450 4450);
PAINT MONO (-2450 4450);
DISPLAY INVISIBLE (-2450 4450);
FORCEPROP 1 LAST PATH I6
J 0
(-2450 4400);
DISPLAY 0.978723 (-2450 4400);
PAINT WHITE (-2450 4400);
DISPLAY INVISIBLE (-2450 4400);
FORCEADD PVCCIO_CPU0..1
R 6
(-7850 2925);
FORCEPROP 3 LASTPIN (-7850 2975) SIG_NAME PVCCIO_CPU0\g
J 0
(-7840 2985);
DISPLAY 0.659574 (-7840 2985);
PAINT MONO (-7840 2985);
DISPLAY INVISIBLE (-7840 2985);
FORCEPROP 1 LAST PATH I60
J 0
(-7800 2900);
DISPLAY 0.872340 (-7800 2900);
PAINT AQUA (-7800 2900);
DISPLAY INVISIBLE (-7800 2900);
FORCEPROP 1 LAST VOLTAGE 1.1V
J 0
(-7895 2968);
DISPLAY 0.340426 (-7895 2968);
PAINT SKYBLUE (-7895 2968);
DISPLAY INVISIBLE (-7895 2968);
FORCEPROP 2 LAST CDS_LIB mstr_symbols
J 0
(-7850 2925);
PAINT ORANGE (-7850 2925);
DISPLAY INVISIBLE (-7850 2925);
FORCEPROP 1 LAST BODY_TYPE PLUMBING
J 0
(-7895 2968);
DISPLAY 0.340426 (-7895 2968);
PAINT GREEN (-7895 2968);
DISPLAY INVISIBLE (-7895 2968);
FORCEPROP 1 LAST HDL_POWER PVCCIO_CPU0
J 1
(-7850 2875);
DISPLAY 0.872340 (-7850 2875);
PAINT GREEN (-7850 2875);
DISPLAY INVISIBLE (-7850 2875);
FORCEADD RES..2
(-8250 3275);
FORCEPROP 1 LAST PACK_TYPE 0402
J 0
(-8210 3025);
DISPLAY 0.617021 (-8210 3025);
PAINT SKYBLUE (-8210 3025);
FORCEPROP 1 LAST PART_NUMBER G21796-009
J 0
(-8210 3125);
DISPLAY 0.617021 (-8210 3125);
PAINT BLUE (-8210 3125);
FORCEPROP 1 LAST VALUE 150.0
J 0
(-8205 3350);
DISPLAY 0.617021 (-8205 3350);
PAINT SKYBLUE (-8205 3350);
FORCEPROP 1 LAST TOLERANCE 1%
J 0
(-8205 3300);
DISPLAY 0.617021 (-8205 3300);
PAINT SKYBLUE (-8205 3300);
FORCEPROP 1 LAST MATERIAL CHIP
J 0
(-8210 3200);
DISPLAY 0.617021 (-8210 3200);
PAINT SKYBLUE (-8210 3200);
FORCEPROP 1 LAST WATTAGE 1/16W
J 0
(-8210 3250);
DISPLAY 0.617021 (-8210 3250);
PAINT SKYBLUE (-8210 3250);
FORCEPROP 1 LASTPIN (-8250 3375) $PN 1
J 0
(-8245 3337);
DISPLAY 0.617021 (-8245 3337);
PAINT ORANGE (-8245 3337);
FORCEPROP 1 LASTPIN (-8250 3175) $PN 2
J 0
(-8245 3185);
DISPLAY 0.617021 (-8245 3185);
PAINT ORANGE (-8245 3185);
FORCEPROP 1 LAST LOCATION R7P5
J 0
(-8205 3400);
DISPLAY 0.617021 (-8205 3400);
PAINT AQUA (-8205 3400);
FORCEPROP 2 LAST SEC_TYPE 0402
J 0
(-8200 3500);
DISPLAY 1.021277 (-8200 3500);
PAINT ORANGE (-8200 3500);
DISPLAY INVISIBLE (-8200 3500);
FORCEPROP 2 LAST SEC 1
J 0
(-8200 3500);
DISPLAY 0.680851 (-8200 3500);
PAINT MONO (-8200 3500);
DISPLAY INVISIBLE (-8200 3500);
FORCEPROP 2 LAST CDS_LOCATION R7P5
J 0
(-8205 3400);
DISPLAY 0.617021 (-8205 3400);
PAINT AQUA (-8205 3400);
DISPLAY INVISIBLE (-8205 3400);
FORCEPROP 1 LAST PATH I61
J 0
(-8200 3450);
DISPLAY 0.978723 (-8200 3450);
PAINT WHITE (-8200 3450);
DISPLAY INVISIBLE (-8200 3450);
FORCEPROP 2 LAST CDS_LIB mstr_discrete
J 0
(-8250 3275);
PAINT MONO (-8250 3275);
DISPLAY INVISIBLE (-8250 3275);
FORCEPROP 2 LAST BOM_COST PROC_SIDEBAND
J 0
(-8250 3275);
PAINT MONO (-8250 3275);
DISPLAY INVISIBLE (-8250 3275);
FORCEPROP 2 LAST ROOM PROC_SIDEBAND
J 0
(-8225 3050);
PAINT ORANGE (-8225 3050);
DISPLAY INVISIBLE (-8225 3050);
FORCEADD RES..2
R 2
(-8350 3275);
FORCEPROP 1 LASTPIN (-8350 3375) $PN 1
J 2
(-8355 3337);
DISPLAY 0.617021 (-8355 3337);
PAINT ORANGE (-8355 3337);
FORCEPROP 1 LASTPIN (-8350 3175) $PN 2
J 2
(-8355 3185);
DISPLAY 0.617021 (-8355 3185);
PAINT ORANGE (-8355 3185);
FORCEPROP 1 LAST LOCATION R7P21
J 2
(-8395 3400);
DISPLAY 0.617021 (-8395 3400);
PAINT AQUA (-8395 3400);
FORCEPROP 1 LAST PART_NUMBER G21796-009
J 2
(-8390 3150);
DISPLAY 0.617021 (-8390 3150);
PAINT BLUE (-8390 3150);
FORCEPROP 1 LAST VALUE 150.0
J 2
(-8395 3350);
DISPLAY 0.617021 (-8395 3350);
PAINT SKYBLUE (-8395 3350);
FORCEPROP 1 LAST TOLERANCE 1%
J 2
(-8395 3300);
DISPLAY 0.617021 (-8395 3300);
PAINT SKYBLUE (-8395 3300);
FORCEPROP 1 LAST PACK_TYPE 0402
J 2
(-8390 3100);
DISPLAY 0.617021 (-8390 3100);
PAINT SKYBLUE (-8390 3100);
FORCEPROP 1 LAST MATERIAL CHIP
J 2
(-8390 3200);
DISPLAY 0.617021 (-8390 3200);
PAINT SKYBLUE (-8390 3200);
FORCEPROP 1 LAST WATTAGE 1/16W
J 2
(-8390 3250);
DISPLAY 0.617021 (-8390 3250);
PAINT SKYBLUE (-8390 3250);
FORCEPROP 2 LAST SEC_TYPE 0402
J 0
(-8400 3500);
DISPLAY 1.021277 (-8400 3500);
PAINT ORANGE (-8400 3500);
DISPLAY INVISIBLE (-8400 3500);
FORCEPROP 2 LAST SEC 1
J 0
(-8400 3500);
DISPLAY 0.680851 (-8400 3500);
PAINT MONO (-8400 3500);
DISPLAY INVISIBLE (-8400 3500);
FORCEPROP 2 LAST CDS_LOCATION R7P21
J 2
(-8395 3400);
DISPLAY 0.617021 (-8395 3400);
PAINT AQUA (-8395 3400);
DISPLAY INVISIBLE (-8395 3400);
FORCEPROP 1 LAST PATH I62
J 2
(-8400 3450);
DISPLAY 0.978723 (-8400 3450);
PAINT WHITE (-8400 3450);
DISPLAY INVISIBLE (-8400 3450);
FORCEPROP 2 LAST CDS_LIB mstr_discrete
J 0
(-8350 3275);
PAINT MONO (-8350 3275);
DISPLAY INVISIBLE (-8350 3275);
FORCEPROP 2 LAST BOM_COST PROC_SIDEBAND
J 2
(-8350 3275);
PAINT MONO (-8350 3275);
DISPLAY INVISIBLE (-8350 3275);
FORCEPROP 2 LAST ROOM PROC_SIDEBAND
J 2
(-8375 3050);
PAINT ORANGE (-8375 3050);
DISPLAY INVISIBLE (-8375 3050);
FORCEADD PVCCIO_CPU1..1
R 6
(-8300 2925);
FORCEPROP 3 LASTPIN (-8300 2975) SIG_NAME PVCCIO_CPU1\g
J 0
(-8290 2985);
DISPLAY 0.659574 (-8290 2985);
PAINT MONO (-8290 2985);
DISPLAY INVISIBLE (-8290 2985);
FORCEPROP 2 LAST CDS_LIB mstr_symbols
J 0
(-8300 2925);
PAINT ORANGE (-8300 2925);
DISPLAY INVISIBLE (-8300 2925);
FORCEPROP 1 LAST PATH I63
J 0
(-8250 2900);
DISPLAY 0.872340 (-8250 2900);
PAINT AQUA (-8250 2900);
DISPLAY INVISIBLE (-8250 2900);
FORCEPROP 1 LAST VOLTAGE 1.1V
J 0
(-8345 2968);
DISPLAY 0.340426 (-8345 2968);
PAINT SKYBLUE (-8345 2968);
DISPLAY INVISIBLE (-8345 2968);
FORCEPROP 1 LAST BODY_TYPE PLUMBING
J 0
(-8345 2968);
DISPLAY 0.340426 (-8345 2968);
PAINT GREEN (-8345 2968);
DISPLAY INVISIBLE (-8345 2968);
FORCEPROP 1 LAST HDL_POWER PVCCIO_CPU1
J 1
(-8300 2875);
DISPLAY 0.872340 (-8300 2875);
PAINT GREEN (-8300 2875);
DISPLAY INVISIBLE (-8300 2875);
FORCEADD RES..1
(-6950 3900);
FORCEPROP 1 LAST VALUE 0.0
J 2
(-7050 3900);
DISPLAY 0.617021 (-7050 3900);
PAINT SKYBLUE (-7050 3900);
FORCEPROP 1 LASTPIN (-7050 3900) $PN 1
J 0
(-7038 3912);
DISPLAY 0.617021 (-7038 3912);
PAINT ORANGE (-7038 3912);
FORCEPROP 1 LAST LOCATION R1U53
J 0
(-7150 3950);
DISPLAY 0.617021 (-7150 3950);
PAINT AQUA (-7150 3950);
FORCEPROP 1 LASTPIN (-6850 3900) $PN 2
J 0
(-6888 3912);
DISPLAY 0.617021 (-6888 3912);
PAINT ORANGE (-6888 3912);
FORCEPROP 1 LAST MATERIAL CHIP
J 0
(-6875 3850);
DISPLAY 0.617021 (-6875 3850);
PAINT SKYBLUE (-6875 3850);
FORCEPROP 1 LAST PART_NUMBER G21497-005
J 0
(-7150 3850);
DISPLAY 0.617021 (-7150 3850);
PAINT BLUE (-7150 3850);
FORCEPROP 1 LAST WATTAGE 1/16W
J 0
(-6850 3950);
DISPLAY 0.617021 (-6850 3950);
PAINT SKYBLUE (-6850 3950);
FORCEPROP 1 LAST PACK_TYPE 0402
J 0
(-6850 3900);
DISPLAY 0.617021 (-6850 3900);
PAINT SKYBLUE (-6850 3900);
FORCEPROP 1 LAST TOLERANCE 5%
J 0
(-6950 3950);
DISPLAY 0.617021 (-6950 3950);
PAINT SKYBLUE (-6950 3950);
FORCEPROP 2 LAST SEC_TYPE 0402
J 0
(-7000 4100);
DISPLAY 1.021277 (-7000 4100);
PAINT ORANGE (-7000 4100);
DISPLAY INVISIBLE (-7000 4100);
FORCEPROP 2 LAST SEC 1
J 0
(-7000 4100);
DISPLAY 0.680851 (-7000 4100);
PAINT MONO (-7000 4100);
DISPLAY INVISIBLE (-7000 4100);
FORCEPROP 1 LAST PATH I64
J 0
(-7000 4050);
DISPLAY 0.978723 (-7000 4050);
PAINT WHITE (-7000 4050);
DISPLAY INVISIBLE (-7000 4050);
FORCEPROP 2 LAST CDS_LIB mstr_discrete
J 0
(-6950 3900);
PAINT ORANGE (-6950 3900);
DISPLAY INVISIBLE (-6950 3900);
FORCEADD RES..1
(-6950 3750);
FORCEPROP 1 LAST VALUE 0.0
J 2
(-7050 3750);
DISPLAY 0.617021 (-7050 3750);
PAINT SKYBLUE (-7050 3750);
FORCEPROP 1 LAST LOCATION R1U60
J 0
(-7150 3800);
DISPLAY 0.617021 (-7150 3800);
PAINT AQUA (-7150 3800);
FORCEPROP 1 LASTPIN (-7050 3750) $PN 1
J 0
(-7038 3762);
DISPLAY 0.617021 (-7038 3762);
PAINT ORANGE (-7038 3762);
FORCEPROP 1 LAST PART_NUMBER G21497-005
J 0
(-7150 3700);
DISPLAY 0.617021 (-7150 3700);
PAINT BLUE (-7150 3700);
FORCEPROP 1 LAST TOLERANCE 5%
J 0
(-6950 3800);
DISPLAY 0.617021 (-6950 3800);
PAINT SKYBLUE (-6950 3800);
FORCEPROP 1 LASTPIN (-6850 3750) $PN 2
J 0
(-6888 3762);
DISPLAY 0.617021 (-6888 3762);
PAINT ORANGE (-6888 3762);
FORCEPROP 1 LAST WATTAGE 1/16W
J 0
(-6850 3800);
DISPLAY 0.617021 (-6850 3800);
PAINT SKYBLUE (-6850 3800);
FORCEPROP 1 LAST MATERIAL CHIP
J 0
(-6875 3700);
DISPLAY 0.617021 (-6875 3700);
PAINT SKYBLUE (-6875 3700);
FORCEPROP 1 LAST PACK_TYPE 0402
J 0
(-6850 3750);
DISPLAY 0.617021 (-6850 3750);
PAINT SKYBLUE (-6850 3750);
FORCEPROP 2 LAST SEC 1
J 0
(-7000 3950);
DISPLAY 0.680851 (-7000 3950);
PAINT MONO (-7000 3950);
DISPLAY INVISIBLE (-7000 3950);
FORCEPROP 2 LAST SEC_TYPE 0402
J 0
(-7000 3950);
DISPLAY 1.021277 (-7000 3950);
PAINT ORANGE (-7000 3950);
DISPLAY INVISIBLE (-7000 3950);
FORCEPROP 1 LAST PATH I65
J 0
(-7000 3900);
DISPLAY 0.978723 (-7000 3900);
PAINT WHITE (-7000 3900);
DISPLAY INVISIBLE (-7000 3900);
FORCEPROP 2 LAST CDS_LIB mstr_discrete
J 0
(-6950 3750);
PAINT ORANGE (-6950 3750);
DISPLAY INVISIBLE (-6950 3750);
FORCEADD RES..2
(-2850 4600);
FORCEPROP 1 LAST LOCATION R2U49
J 0
(-2805 4725);
DISPLAY 0.617021 (-2805 4725);
PAINT AQUA (-2805 4725);
FORCEPROP 1 LAST VALUE 0.0
J 0
(-2805 4675);
DISPLAY 0.617021 (-2805 4675);
PAINT SKYBLUE (-2805 4675);
FORCEPROP 1 LAST TOLERANCE 5%
J 0
(-2805 4625);
DISPLAY 0.617021 (-2805 4625);
PAINT SKYBLUE (-2805 4625);
FORCEPROP 1 LASTPIN (-2850 4700) $PN 1
J 0
(-2845 4662);
DISPLAY 0.617021 (-2845 4662);
PAINT ORANGE (-2845 4662);
FORCEPROP 1 LAST MATERIAL EMPTY
J 0
(-2810 4525);
DISPLAY 0.617021 (-2810 4525);
PAINT RED (-2810 4525);
FORCEPROP 1 LAST WATTAGE 1/16W
J 0
(-2810 4575);
DISPLAY 0.617021 (-2810 4575);
PAINT SKYBLUE (-2810 4575);
FORCEPROP 1 LAST PACK_TYPE 0402
J 0
(-2810 4425);
DISPLAY 0.617021 (-2810 4425);
PAINT SKYBLUE (-2810 4425);
FORCEPROP 1 LASTPIN (-2850 4500) $PN 2
J 0
(-2845 4510);
DISPLAY 0.617021 (-2845 4510);
PAINT ORANGE (-2845 4510);
FORCEPROP 1 LAST PART_NUMBER G21497-005
J 0
(-2810 4475);
DISPLAY 0.617021 (-2810 4475);
PAINT BLUE (-2810 4475);
FORCEPROP 2 LAST SEC_TYPE 0402
J 0
(-2800 4825);
DISPLAY 1.021277 (-2800 4825);
PAINT ORANGE (-2800 4825);
DISPLAY INVISIBLE (-2800 4825);
FORCEPROP 2 LAST SEC 1
J 0
(-2800 4825);
DISPLAY 0.680851 (-2800 4825);
PAINT MONO (-2800 4825);
DISPLAY INVISIBLE (-2800 4825);
FORCEPROP 1 LAST PATH I66
J 0
(-2800 4775);
DISPLAY 0.978723 (-2800 4775);
PAINT WHITE (-2800 4775);
DISPLAY INVISIBLE (-2800 4775);
FORCEPROP 2 LAST CDS_LIB mstr_discrete
J 0
(-2850 4600);
PAINT ORANGE (-2850 4600);
DISPLAY INVISIBLE (-2850 4600);
FORCEADD RES..2
(-7175 3500);
FORCEPROP 1 LAST MATERIAL EMPTY
J 0
(-7135 3425);
DISPLAY 0.617021 (-7135 3425);
PAINT RED (-7135 3425);
FORCEPROP 1 LAST PACK_TYPE 0402
J 0
(-7135 3325);
DISPLAY 0.617021 (-7135 3325);
PAINT SKYBLUE (-7135 3325);
FORCEPROP 1 LASTPIN (-7175 3400) $PN 2
J 0
(-7170 3410);
DISPLAY 0.617021 (-7170 3410);
PAINT ORANGE (-7170 3410);
FORCEPROP 1 LASTPIN (-7175 3600) $PN 1
J 0
(-7170 3562);
DISPLAY 0.617021 (-7170 3562);
PAINT ORANGE (-7170 3562);
FORCEPROP 1 LAST PART_NUMBER G21497-005
J 0
(-7135 3375);
DISPLAY 0.617021 (-7135 3375);
PAINT BLUE (-7135 3375);
FORCEPROP 1 LAST WATTAGE 1/16W
J 0
(-7135 3475);
DISPLAY 0.617021 (-7135 3475);
PAINT SKYBLUE (-7135 3475);
FORCEPROP 1 LAST TOLERANCE 5%
J 0
(-7130 3525);
DISPLAY 0.617021 (-7130 3525);
PAINT SKYBLUE (-7130 3525);
FORCEPROP 1 LAST VALUE 0.0
J 0
(-7130 3575);
DISPLAY 0.617021 (-7130 3575);
PAINT SKYBLUE (-7130 3575);
FORCEPROP 1 LAST LOCATION R1U55
J 0
(-7130 3625);
DISPLAY 0.617021 (-7130 3625);
PAINT AQUA (-7130 3625);
FORCEPROP 1 LAST PATH I67
J 0
(-7125 3675);
DISPLAY 0.978723 (-7125 3675);
PAINT WHITE (-7125 3675);
DISPLAY INVISIBLE (-7125 3675);
FORCEPROP 2 LAST SEC 1
J 0
(-7125 3725);
DISPLAY 0.680851 (-7125 3725);
PAINT MONO (-7125 3725);
DISPLAY INVISIBLE (-7125 3725);
FORCEPROP 2 LAST SEC_TYPE 0402
J 0
(-7125 3725);
DISPLAY 1.021277 (-7125 3725);
PAINT ORANGE (-7125 3725);
DISPLAY INVISIBLE (-7125 3725);
FORCEPROP 2 LAST CDS_LIB mstr_discrete
J 0
(-7175 3500);
PAINT ORANGE (-7175 3500);
DISPLAY INVISIBLE (-7175 3500);
FORCEADD RES..2
(-7450 3500);
FORCEPROP 1 LAST LOCATION R1U62
J 0
(-7405 3625);
DISPLAY 0.617021 (-7405 3625);
PAINT AQUA (-7405 3625);
FORCEPROP 1 LASTPIN (-7450 3600) $PN 1
J 0
(-7445 3562);
DISPLAY 0.617021 (-7445 3562);
PAINT ORANGE (-7445 3562);
FORCEPROP 1 LAST VALUE 0.0
J 0
(-7405 3575);
DISPLAY 0.617021 (-7405 3575);
PAINT SKYBLUE (-7405 3575);
FORCEPROP 1 LAST MATERIAL EMPTY
J 0
(-7410 3425);
DISPLAY 0.617021 (-7410 3425);
PAINT RED (-7410 3425);
FORCEPROP 1 LAST WATTAGE 1/16W
J 0
(-7410 3475);
DISPLAY 0.617021 (-7410 3475);
PAINT SKYBLUE (-7410 3475);
FORCEPROP 1 LAST TOLERANCE 5%
J 0
(-7405 3525);
DISPLAY 0.617021 (-7405 3525);
PAINT SKYBLUE (-7405 3525);
FORCEPROP 1 LAST PACK_TYPE 0402
J 0
(-7410 3325);
DISPLAY 0.617021 (-7410 3325);
PAINT SKYBLUE (-7410 3325);
FORCEPROP 1 LASTPIN (-7450 3400) $PN 2
J 0
(-7445 3410);
DISPLAY 0.617021 (-7445 3410);
PAINT ORANGE (-7445 3410);
FORCEPROP 1 LAST PART_NUMBER G21497-005
J 0
(-7410 3375);
DISPLAY 0.617021 (-7410 3375);
PAINT BLUE (-7410 3375);
FORCEPROP 2 LAST SEC_TYPE 0402
J 0
(-7400 3725);
DISPLAY 1.021277 (-7400 3725);
PAINT ORANGE (-7400 3725);
DISPLAY INVISIBLE (-7400 3725);
FORCEPROP 2 LAST SEC 1
J 0
(-7400 3725);
DISPLAY 0.680851 (-7400 3725);
PAINT MONO (-7400 3725);
DISPLAY INVISIBLE (-7400 3725);
FORCEPROP 1 LAST PATH I68
J 0
(-7400 3675);
DISPLAY 0.978723 (-7400 3675);
PAINT WHITE (-7400 3675);
DISPLAY INVISIBLE (-7400 3675);
FORCEPROP 2 LAST CDS_LIB mstr_discrete
J 0
(-7450 3500);
PAINT ORANGE (-7450 3500);
DISPLAY INVISIBLE (-7450 3500);
FORCEADD RES..2
(-3175 3425);
FORCEPROP 1 LAST PACK_TYPE 0402
J 0
(-3135 3250);
DISPLAY 0.617021 (-3135 3250);
PAINT SKYBLUE (-3135 3250);
FORCEPROP 1 LAST MATERIAL EMPTY
J 0
(-3135 3350);
DISPLAY 0.617021 (-3135 3350);
PAINT RED (-3135 3350);
FORCEPROP 1 LASTPIN (-3175 3325) $PN 2
J 0
(-3170 3335);
DISPLAY 0.617021 (-3170 3335);
PAINT ORANGE (-3170 3335);
FORCEPROP 1 LAST LOCATION R1U57
J 0
(-3130 3550);
DISPLAY 0.617021 (-3130 3550);
PAINT AQUA (-3130 3550);
FORCEPROP 1 LAST VALUE 0.0
J 0
(-3130 3500);
DISPLAY 0.617021 (-3130 3500);
PAINT SKYBLUE (-3130 3500);
FORCEPROP 1 LAST TOLERANCE 5%
J 0
(-3130 3450);
DISPLAY 0.617021 (-3130 3450);
PAINT SKYBLUE (-3130 3450);
FORCEPROP 1 LAST WATTAGE 1/16W
J 0
(-3135 3400);
DISPLAY 0.617021 (-3135 3400);
PAINT SKYBLUE (-3135 3400);
FORCEPROP 1 LAST PART_NUMBER G21497-005
J 0
(-3135 3300);
DISPLAY 0.617021 (-3135 3300);
PAINT BLUE (-3135 3300);
FORCEPROP 1 LASTPIN (-3175 3525) $PN 1
J 0
(-3170 3487);
DISPLAY 0.617021 (-3170 3487);
PAINT ORANGE (-3170 3487);
FORCEPROP 1 LAST PATH I69
J 0
(-3125 3600);
DISPLAY 0.978723 (-3125 3600);
PAINT WHITE (-3125 3600);
DISPLAY INVISIBLE (-3125 3600);
FORCEPROP 2 LAST SEC 1
J 0
(-3125 3650);
DISPLAY 0.680851 (-3125 3650);
PAINT MONO (-3125 3650);
DISPLAY INVISIBLE (-3125 3650);
FORCEPROP 2 LAST SEC_TYPE 0402
J 0
(-3125 3650);
DISPLAY 1.021277 (-3125 3650);
PAINT ORANGE (-3125 3650);
DISPLAY INVISIBLE (-3125 3650);
FORCEPROP 2 LAST CDS_LIB mstr_discrete
J 0
(-3175 3425);
PAINT ORANGE (-3175 3425);
DISPLAY INVISIBLE (-3175 3425);
FORCEADD RES..2
(-2875 3425);
FORCEPROP 1 LAST VALUE 0.0
J 0
(-2830 3500);
DISPLAY 0.617021 (-2830 3500);
PAINT SKYBLUE (-2830 3500);
FORCEPROP 1 LAST TOLERANCE 5%
J 0
(-2830 3450);
DISPLAY 0.617021 (-2830 3450);
PAINT SKYBLUE (-2830 3450);
FORCEPROP 1 LAST WATTAGE 1/16W
J 0
(-2835 3400);
DISPLAY 0.617021 (-2835 3400);
PAINT SKYBLUE (-2835 3400);
FORCEPROP 1 LAST PART_NUMBER G21497-005
J 0
(-2835 3300);
DISPLAY 0.617021 (-2835 3300);
PAINT BLUE (-2835 3300);
FORCEPROP 1 LAST MATERIAL EMPTY
J 0
(-2835 3350);
DISPLAY 0.617021 (-2835 3350);
PAINT RED (-2835 3350);
FORCEPROP 1 LAST LOCATION R1U61
J 0
(-2830 3550);
DISPLAY 0.617021 (-2830 3550);
PAINT AQUA (-2830 3550);
FORCEPROP 1 LAST PACK_TYPE 0402
J 0
(-2835 3250);
DISPLAY 0.617021 (-2835 3250);
PAINT SKYBLUE (-2835 3250);
FORCEPROP 1 LASTPIN (-2875 3525) $PN 1
J 0
(-2870 3487);
DISPLAY 0.617021 (-2870 3487);
PAINT ORANGE (-2870 3487);
FORCEPROP 1 LASTPIN (-2875 3325) $PN 2
J 0
(-2870 3335);
DISPLAY 0.617021 (-2870 3335);
PAINT ORANGE (-2870 3335);
FORCEPROP 2 LAST SEC_TYPE 0402
J 0
(-2825 3650);
DISPLAY 1.021277 (-2825 3650);
PAINT ORANGE (-2825 3650);
DISPLAY INVISIBLE (-2825 3650);
FORCEPROP 2 LAST SEC 1
J 0
(-2825 3650);
DISPLAY 0.680851 (-2825 3650);
PAINT MONO (-2825 3650);
DISPLAY INVISIBLE (-2825 3650);
FORCEPROP 1 LAST PATH I70
J 0
(-2825 3600);
DISPLAY 0.978723 (-2825 3600);
PAINT WHITE (-2825 3600);
DISPLAY INVISIBLE (-2825 3600);
FORCEPROP 2 LAST CDS_LIB mstr_discrete
J 0
(-2875 3425);
PAINT ORANGE (-2875 3425);
DISPLAY INVISIBLE (-2875 3425);
FORCEADD RES..1
(-3375 3725);
FORCEPROP 1 LASTPIN (-3275 3725) $PN 2
J 0
(-3313 3737);
DISPLAY 0.617021 (-3313 3737);
PAINT ORANGE (-3313 3737);
FORCEPROP 1 LAST VALUE 0.0
J 2
(-3475 3725);
DISPLAY 0.617021 (-3475 3725);
PAINT SKYBLUE (-3475 3725);
FORCEPROP 1 LAST PACK_TYPE 0402
J 0
(-3400 3525);
DISPLAY 0.617021 (-3400 3525);
PAINT SKYBLUE (-3400 3525);
FORCEPROP 1 LAST WATTAGE 1/16W
J 0
(-3400 3575);
DISPLAY 0.617021 (-3400 3575);
PAINT SKYBLUE (-3400 3575);
FORCEPROP 1 LAST TOLERANCE 5%
J 0
(-3400 3625);
DISPLAY 0.617021 (-3400 3625);
PAINT SKYBLUE (-3400 3625);
FORCEPROP 1 LAST PART_NUMBER G21497-005
J 0
(-3400 3675);
DISPLAY 0.617021 (-3400 3675);
PAINT BLUE (-3400 3675);
FORCEPROP 1 LAST LOCATION R9G28
J 0
(-3425 3775);
DISPLAY 0.617021 (-3425 3775);
PAINT AQUA (-3425 3775);
FORCEPROP 1 LAST MATERIAL CHIP
J 0
(-3500 3675);
DISPLAY 0.617021 (-3500 3675);
PAINT SKYBLUE (-3500 3675);
FORCEPROP 1 LASTPIN (-3475 3725) $PN 1
J 0
(-3463 3737);
DISPLAY 0.617021 (-3463 3737);
PAINT ORANGE (-3463 3737);
FORCEPROP 2 LAST SEC_TYPE 0402
J 0
(-3425 3925);
DISPLAY 1.021277 (-3425 3925);
PAINT ORANGE (-3425 3925);
DISPLAY INVISIBLE (-3425 3925);
FORCEPROP 2 LAST SEC 1
J 0
(-3425 3925);
DISPLAY 0.680851 (-3425 3925);
PAINT MONO (-3425 3925);
DISPLAY INVISIBLE (-3425 3925);
FORCEPROP 1 LAST PATH I71
J 0
(-3425 3875);
DISPLAY 0.978723 (-3425 3875);
PAINT WHITE (-3425 3875);
DISPLAY INVISIBLE (-3425 3875);
FORCEPROP 2 LAST CDS_LIB mstr_discrete
J 0
(-3375 3725);
PAINT ORANGE (-3375 3725);
DISPLAY INVISIBLE (-3375 3725);
FORCEADD RES..1
(-3375 3900);
FORCEPROP 1 LAST PART_NUMBER G21497-005
J 0
(-3400 3850);
DISPLAY 0.617021 (-3400 3850);
PAINT BLUE (-3400 3850);
FORCEPROP 1 LASTPIN (-3475 3900) $PN 1
J 0
(-3463 3912);
DISPLAY 0.617021 (-3463 3912);
PAINT ORANGE (-3463 3912);
FORCEPROP 1 LAST WATTAGE 1/16W
J 0
(-2850 3850);
DISPLAY 0.617021 (-2850 3850);
PAINT SKYBLUE (-2850 3850);
FORCEPROP 1 LAST TOLERANCE 5%
J 0
(-2975 3850);
DISPLAY 0.617021 (-2975 3850);
PAINT SKYBLUE (-2975 3850);
FORCEPROP 1 LAST PACK_TYPE 0402
J 0
(-3125 3850);
DISPLAY 0.617021 (-3125 3850);
PAINT SKYBLUE (-3125 3850);
FORCEPROP 1 LASTPIN (-3275 3900) $PN 2
J 0
(-3313 3912);
DISPLAY 0.617021 (-3313 3912);
PAINT ORANGE (-3313 3912);
FORCEPROP 1 LAST VALUE 0.0
J 2
(-3475 3900);
DISPLAY 0.617021 (-3475 3900);
PAINT SKYBLUE (-3475 3900);
FORCEPROP 1 LAST LOCATION R9G32
J 0
(-3425 3950);
DISPLAY 0.617021 (-3425 3950);
PAINT AQUA (-3425 3950);
FORCEPROP 1 LAST MATERIAL CHIP
J 0
(-3500 3850);
DISPLAY 0.617021 (-3500 3850);
PAINT SKYBLUE (-3500 3850);
FORCEPROP 2 LAST SEC 1
J 0
(-3425 4100);
DISPLAY 0.680851 (-3425 4100);
PAINT MONO (-3425 4100);
DISPLAY INVISIBLE (-3425 4100);
FORCEPROP 2 LAST SEC_TYPE 0402
J 0
(-3425 4100);
DISPLAY 1.021277 (-3425 4100);
PAINT ORANGE (-3425 4100);
DISPLAY INVISIBLE (-3425 4100);
FORCEPROP 1 LAST PATH I72
J 0
(-3425 4050);
DISPLAY 0.978723 (-3425 4050);
PAINT WHITE (-3425 4050);
DISPLAY INVISIBLE (-3425 4050);
FORCEPROP 2 LAST CDS_LIB mstr_discrete
J 0
(-3375 3900);
PAINT ORANGE (-3375 3900);
DISPLAY INVISIBLE (-3375 3900);
FORCEADD RES..1
(-3375 4075);
FORCEPROP 1 LAST VALUE 0.0
J 2
(-3475 4075);
DISPLAY 0.617021 (-3475 4075);
PAINT SKYBLUE (-3475 4075);
FORCEPROP 1 LASTPIN (-3275 4075) $PN 2
J 0
(-3313 4087);
DISPLAY 0.617021 (-3313 4087);
PAINT ORANGE (-3313 4087);
FORCEPROP 1 LAST LOCATION R9G33
J 0
(-3425 4125);
DISPLAY 0.617021 (-3425 4125);
PAINT AQUA (-3425 4125);
FORCEPROP 1 LAST TOLERANCE 5%
J 0
(-2975 4025);
DISPLAY 0.617021 (-2975 4025);
PAINT SKYBLUE (-2975 4025);
FORCEPROP 1 LAST PACK_TYPE 0402
J 0
(-3125 4025);
DISPLAY 0.617021 (-3125 4025);
PAINT SKYBLUE (-3125 4025);
FORCEPROP 1 LAST WATTAGE 1/16W
J 2
(-2750 4025);
DISPLAY 0.617021 (-2750 4025);
PAINT SKYBLUE (-2750 4025);
FORCEPROP 1 LAST MATERIAL CHIP
J 0
(-3500 4025);
DISPLAY 0.617021 (-3500 4025);
PAINT SKYBLUE (-3500 4025);
FORCEPROP 1 LAST PART_NUMBER G21497-005
J 0
(-3400 4025);
DISPLAY 0.617021 (-3400 4025);
PAINT BLUE (-3400 4025);
FORCEPROP 1 LASTPIN (-3475 4075) $PN 1
J 0
(-3463 4087);
DISPLAY 0.617021 (-3463 4087);
PAINT ORANGE (-3463 4087);
FORCEPROP 1 LAST PATH I73
J 0
(-3425 4225);
DISPLAY 0.978723 (-3425 4225);
PAINT WHITE (-3425 4225);
DISPLAY INVISIBLE (-3425 4225);
FORCEPROP 2 LAST SEC 1
J 0
(-3425 4275);
DISPLAY 0.680851 (-3425 4275);
PAINT MONO (-3425 4275);
DISPLAY INVISIBLE (-3425 4275);
FORCEPROP 2 LAST SEC_TYPE 0402
J 0
(-3425 4275);
DISPLAY 1.021277 (-3425 4275);
PAINT ORANGE (-3425 4275);
DISPLAY INVISIBLE (-3425 4275);
FORCEPROP 2 LAST CDS_LIB mstr_discrete
J 0
(-3375 4075);
PAINT ORANGE (-3375 4075);
DISPLAY INVISIBLE (-3375 4075);
FORCEADD RES..1
(-3375 4250);
FORCEPROP 1 LAST WATTAGE 1/16W
J 0
(-2875 4200);
DISPLAY 0.617021 (-2875 4200);
PAINT SKYBLUE (-2875 4200);
FORCEPROP 1 LASTPIN (-3475 4250) $PN 1
J 0
(-3463 4262);
DISPLAY 0.617021 (-3463 4262);
PAINT ORANGE (-3463 4262);
FORCEPROP 1 LAST MATERIAL CHIP
J 0
(-3500 4200);
DISPLAY 0.617021 (-3500 4200);
PAINT SKYBLUE (-3500 4200);
FORCEPROP 1 LAST TOLERANCE 5%
J 0
(-2975 4200);
DISPLAY 0.617021 (-2975 4200);
PAINT SKYBLUE (-2975 4200);
FORCEPROP 1 LAST PACK_TYPE 0402
J 0
(-3100 4200);
DISPLAY 0.617021 (-3100 4200);
PAINT SKYBLUE (-3100 4200);
FORCEPROP 1 LAST VALUE 0.0
J 2
(-3475 4250);
DISPLAY 0.617021 (-3475 4250);
PAINT SKYBLUE (-3475 4250);
FORCEPROP 1 LAST LOCATION R1U59
J 0
(-3425 4300);
DISPLAY 0.617021 (-3425 4300);
PAINT AQUA (-3425 4300);
FORCEPROP 1 LASTPIN (-3275 4250) $PN 2
J 0
(-3313 4262);
DISPLAY 0.617021 (-3313 4262);
PAINT ORANGE (-3313 4262);
FORCEPROP 1 LAST PART_NUMBER G21497-005
J 0
(-3400 4200);
DISPLAY 0.617021 (-3400 4200);
PAINT BLUE (-3400 4200);
FORCEPROP 1 LAST PATH I74
J 0
(-3425 4400);
DISPLAY 0.978723 (-3425 4400);
PAINT WHITE (-3425 4400);
DISPLAY INVISIBLE (-3425 4400);
FORCEPROP 2 LAST SEC 1
J 0
(-3425 4450);
DISPLAY 0.680851 (-3425 4450);
PAINT MONO (-3425 4450);
DISPLAY INVISIBLE (-3425 4450);
FORCEPROP 2 LAST SEC_TYPE 0402
J 0
(-3425 4450);
DISPLAY 1.021277 (-3425 4450);
PAINT ORANGE (-3425 4450);
DISPLAY INVISIBLE (-3425 4450);
FORCEPROP 2 LAST CDS_LIB mstr_discrete
J 0
(-3375 4250);
PAINT ORANGE (-3375 4250);
DISPLAY INVISIBLE (-3375 4250);
FORCEADD OFFPAGE..1
(-8000 2475);
FORCEPROP 2 LAST $XR0 152 
J 0
(-8252 2475);
DISPLAY 0.638298 (-8252 2475);
PAINT MONO (-8252 2475);
FORCEPROP 2 LAST CDS_LIB mstr_standard
J 0
(-8000 2475);
PAINT ORANGE (-8000 2475);
DISPLAY INVISIBLE (-8000 2475);
FORCEPROP 2 LAST PATH I75
J 0
(-7675 2525);
DISPLAY 1.021277 (-7675 2525);
PAINT ORANGE (-7675 2525);
DISPLAY INVISIBLE (-7675 2525);
FORCEPROP 1 LAST OFFPAGE TRUE
J 0
(-7675 2350);
DISPLAY 0.872340 (-7675 2350);
PAINT GREEN (-7675 2350);
DISPLAY INVISIBLE (-7675 2350);
FORCEPROP 1 LAST COMMENT_BODY TRUE
J 0
(-7875 2375);
DISPLAY 0.872340 (-7875 2375);
PAINT GREEN (-7875 2375);
DISPLAY INVISIBLE (-7875 2375);
FORCEADD OFFPAGE..1
(-8000 2025);
FORCEPROP 2 LAST $XR0 152 
J 0
(-8252 2025);
DISPLAY 0.638298 (-8252 2025);
PAINT MONO (-8252 2025);
FORCEPROP 2 LAST PATH I76
J 0
(-7675 2075);
DISPLAY 1.021277 (-7675 2075);
PAINT ORANGE (-7675 2075);
DISPLAY INVISIBLE (-7675 2075);
FORCEPROP 2 LAST CDS_LIB mstr_standard
J 0
(-8000 2025);
PAINT ORANGE (-8000 2025);
DISPLAY INVISIBLE (-8000 2025);
FORCEPROP 1 LAST OFFPAGE TRUE
J 0
(-7675 1900);
DISPLAY 0.872340 (-7675 1900);
PAINT GREEN (-7675 1900);
DISPLAY INVISIBLE (-7675 1900);
FORCEPROP 1 LAST COMMENT_BODY TRUE
J 0
(-7875 1925);
DISPLAY 0.872340 (-7875 1925);
PAINT GREEN (-7875 1925);
DISPLAY INVISIBLE (-7875 1925);
FORCEADD OFFPAGE..1
(-8000 1600);
FORCEPROP 2 LAST $XR0 152 
J 0
(-8252 1600);
DISPLAY 0.638298 (-8252 1600);
PAINT MONO (-8252 1600);
FORCEPROP 2 LAST PATH I77
J 0
(-7675 1650);
DISPLAY 1.021277 (-7675 1650);
PAINT ORANGE (-7675 1650);
DISPLAY INVISIBLE (-7675 1650);
FORCEPROP 2 LAST CDS_LIB mstr_standard
J 0
(-8000 1600);
PAINT ORANGE (-8000 1600);
DISPLAY INVISIBLE (-8000 1600);
FORCEPROP 1 LAST OFFPAGE TRUE
J 0
(-7675 1475);
DISPLAY 0.872340 (-7675 1475);
PAINT GREEN (-7675 1475);
DISPLAY INVISIBLE (-7675 1475);
FORCEPROP 1 LAST COMMENT_BODY TRUE
J 0
(-7875 1500);
DISPLAY 0.872340 (-7875 1500);
PAINT GREEN (-7875 1500);
DISPLAY INVISIBLE (-7875 1500);
FORCEADD OFFPAGE..1
(-8000 1175);
FORCEPROP 2 LAST $XR0 152 
J 0
(-8252 1175);
DISPLAY 0.638298 (-8252 1175);
PAINT MONO (-8252 1175);
FORCEPROP 2 LAST CDS_LIB mstr_standard
J 0
(-8000 1175);
PAINT ORANGE (-8000 1175);
DISPLAY INVISIBLE (-8000 1175);
FORCEPROP 2 LAST PATH I78
J 0
(-7675 1225);
DISPLAY 1.021277 (-7675 1225);
PAINT ORANGE (-7675 1225);
DISPLAY INVISIBLE (-7675 1225);
FORCEPROP 1 LAST OFFPAGE TRUE
J 0
(-7675 1050);
DISPLAY 0.872340 (-7675 1050);
PAINT GREEN (-7675 1050);
DISPLAY INVISIBLE (-7675 1050);
FORCEPROP 1 LAST COMMENT_BODY TRUE
J 0
(-7875 1075);
DISPLAY 0.872340 (-7875 1075);
PAINT GREEN (-7875 1075);
DISPLAY INVISIBLE (-7875 1075);
FORCEADD RES..1
(-6700 2475);
FORCEPROP 1 LAST PART_NUMBER G21497-005
J 0
(-6850 2575);
DISPLAY 0.617021 (-6850 2575);
PAINT BLUE (-6850 2575);
FORCEPROP 1 LAST LOCATION R2U47
J 0
(-6750 2525);
DISPLAY 0.617021 (-6750 2525);
PAINT AQUA (-6750 2525);
FORCEPROP 1 LAST MATERIAL CHIP
J 0
(-6700 2425);
DISPLAY 0.617021 (-6700 2425);
PAINT SKYBLUE (-6700 2425);
FORCEPROP 1 LAST PACK_TYPE 0402
J 0
(-6600 2425);
DISPLAY 0.617021 (-6600 2425);
PAINT SKYBLUE (-6600 2425);
FORCEPROP 1 LASTPIN (-6800 2475) $PN 1
J 0
(-6788 2487);
DISPLAY 0.617021 (-6788 2487);
PAINT ORANGE (-6788 2487);
FORCEPROP 1 LAST VALUE 0.0
J 2
(-6800 2475);
DISPLAY 0.617021 (-6800 2475);
PAINT SKYBLUE (-6800 2475);
FORCEPROP 1 LAST WATTAGE 1/16W
J 2
(-6800 2425);
DISPLAY 0.617021 (-6800 2425);
PAINT SKYBLUE (-6800 2425);
FORCEPROP 1 LAST TOLERANCE 5%
J 0
(-6775 2425);
DISPLAY 0.617021 (-6775 2425);
PAINT SKYBLUE (-6775 2425);
FORCEPROP 1 LASTPIN (-6600 2475) $PN 2
J 0
(-6638 2487);
DISPLAY 0.617021 (-6638 2487);
PAINT ORANGE (-6638 2487);
FORCEPROP 0 LAST SEC_TYPE 0402
J 0
(-6725 2650);
DISPLAY 1.021277 (-6725 2650);
PAINT ORANGE (-6725 2650);
DISPLAY INVISIBLE (-6725 2650);
FORCEPROP 2 LAST SEC 1
J 0
(-6750 2675);
DISPLAY 0.680851 (-6750 2675);
PAINT MONO (-6750 2675);
DISPLAY INVISIBLE (-6750 2675);
FORCEPROP 1 LAST PATH I79
J 0
(-6750 2625);
DISPLAY 0.978723 (-6750 2625);
PAINT WHITE (-6750 2625);
DISPLAY INVISIBLE (-6750 2625);
FORCEPROP 2 LAST CDS_LIB mstr_discrete
J 0
(-6700 2475);
PAINT ORANGE (-6700 2475);
DISPLAY INVISIBLE (-6700 2475);
FORCEADD OFFPAGE..2
(-5250 2475);
FORCEPROP 2 LAST $XR0 147 
J 0
(-5061 2475);
DISPLAY 0.638298 (-5061 2475);
PAINT MONO (-5061 2475);
FORCEPROP 2 LAST CDS_LIB mstr_standard
J 0
(-5250 2475);
PAINT ORANGE (-5250 2475);
DISPLAY INVISIBLE (-5250 2475);
FORCEPROP 2 LAST PATH I85
J 0
(-5075 2550);
DISPLAY 1.021277 (-5075 2550);
PAINT ORANGE (-5075 2550);
DISPLAY INVISIBLE (-5075 2550);
FORCEPROP 1 LAST OFFPAGE TRUE
J 0
(-4925 2350);
DISPLAY 0.872340 (-4925 2350);
PAINT GREEN (-4925 2350);
DISPLAY INVISIBLE (-4925 2350);
FORCEPROP 1 LAST COMMENT_BODY TRUE
J 0
(-5295 2380);
DISPLAY 0.872340 (-5295 2380);
PAINT GREEN (-5295 2380);
DISPLAY INVISIBLE (-5295 2380);
FORCEADD OFFPAGE..2
(-5250 2025);
FORCEPROP 2 LAST $XR0 147 
J 0
(-5061 2025);
DISPLAY 0.638298 (-5061 2025);
PAINT MONO (-5061 2025);
FORCEPROP 2 LAST CDS_LIB mstr_standard
J 0
(-5250 2025);
PAINT ORANGE (-5250 2025);
DISPLAY INVISIBLE (-5250 2025);
FORCEPROP 2 LAST PATH I87
J 0
(-5075 2100);
DISPLAY 1.021277 (-5075 2100);
PAINT ORANGE (-5075 2100);
DISPLAY INVISIBLE (-5075 2100);
FORCEPROP 1 LAST OFFPAGE TRUE
J 0
(-4925 1900);
DISPLAY 0.872340 (-4925 1900);
PAINT GREEN (-4925 1900);
DISPLAY INVISIBLE (-4925 1900);
FORCEPROP 1 LAST COMMENT_BODY TRUE
J 0
(-5295 1930);
DISPLAY 0.872340 (-5295 1930);
PAINT GREEN (-5295 1930);
DISPLAY INVISIBLE (-5295 1930);
FORCEADD OFFPAGE..2
(-5250 1600);
FORCEPROP 2 LAST $XR0 147 
J 0
(-5061 1600);
DISPLAY 0.638298 (-5061 1600);
PAINT MONO (-5061 1600);
FORCEPROP 2 LAST CDS_LIB mstr_standard
J 0
(-5250 1600);
PAINT ORANGE (-5250 1600);
DISPLAY INVISIBLE (-5250 1600);
FORCEPROP 2 LAST PATH I89
J 0
(-5075 1675);
DISPLAY 1.021277 (-5075 1675);
PAINT ORANGE (-5075 1675);
DISPLAY INVISIBLE (-5075 1675);
FORCEPROP 1 LAST OFFPAGE TRUE
J 0
(-4925 1475);
DISPLAY 0.872340 (-4925 1475);
PAINT GREEN (-4925 1475);
DISPLAY INVISIBLE (-4925 1475);
FORCEPROP 1 LAST COMMENT_BODY TRUE
J 0
(-5295 1505);
DISPLAY 0.872340 (-5295 1505);
PAINT GREEN (-5295 1505);
DISPLAY INVISIBLE (-5295 1505);
FORCEADD OFFPAGE..2
(-5250 1175);
FORCEPROP 2 LAST $XR0 147 
J 0
(-5061 1175);
DISPLAY 0.638298 (-5061 1175);
PAINT MONO (-5061 1175);
FORCEPROP 2 LAST CDS_LIB mstr_standard
J 0
(-5250 1175);
PAINT ORANGE (-5250 1175);
DISPLAY INVISIBLE (-5250 1175);
FORCEPROP 2 LAST PATH I91
J 0
(-5075 1250);
DISPLAY 1.021277 (-5075 1250);
PAINT ORANGE (-5075 1250);
DISPLAY INVISIBLE (-5075 1250);
FORCEPROP 1 LAST OFFPAGE TRUE
J 0
(-4925 1050);
DISPLAY 0.872340 (-4925 1050);
PAINT GREEN (-4925 1050);
DISPLAY INVISIBLE (-4925 1050);
FORCEPROP 1 LAST COMMENT_BODY TRUE
J 0
(-5295 1080);
DISPLAY 0.872340 (-5295 1080);
PAINT GREEN (-5295 1080);
DISPLAY INVISIBLE (-5295 1080);
FORCEADD RES..1
(-6700 2025);
FORCEPROP 1 LAST PACK_TYPE 0402
J 0
(-6600 1975);
DISPLAY 0.617021 (-6600 1975);
PAINT SKYBLUE (-6600 1975);
FORCEPROP 1 LAST LOCATION R9G29
J 0
(-6750 2075);
DISPLAY 0.617021 (-6750 2075);
PAINT AQUA (-6750 2075);
FORCEPROP 1 LAST PART_NUMBER G21497-005
J 0
(-6850 2125);
DISPLAY 0.617021 (-6850 2125);
PAINT BLUE (-6850 2125);
FORCEPROP 1 LAST MATERIAL CHIP
J 0
(-6700 1975);
DISPLAY 0.617021 (-6700 1975);
PAINT SKYBLUE (-6700 1975);
FORCEPROP 1 LAST TOLERANCE 5%
J 0
(-6775 1975);
DISPLAY 0.617021 (-6775 1975);
PAINT SKYBLUE (-6775 1975);
FORCEPROP 1 LASTPIN (-6600 2025) $PN 2
J 0
(-6638 2037);
DISPLAY 0.617021 (-6638 2037);
PAINT ORANGE (-6638 2037);
FORCEPROP 1 LASTPIN (-6800 2025) $PN 1
J 0
(-6788 2037);
DISPLAY 0.617021 (-6788 2037);
PAINT ORANGE (-6788 2037);
FORCEPROP 1 LAST WATTAGE 1/16W
J 2
(-6800 1975);
DISPLAY 0.617021 (-6800 1975);
PAINT SKYBLUE (-6800 1975);
FORCEPROP 1 LAST VALUE 0.0
J 2
(-6800 2025);
DISPLAY 0.617021 (-6800 2025);
PAINT SKYBLUE (-6800 2025);
FORCEPROP 2 LAST SEC_TYPE 0402
J 0
(-6750 2225);
DISPLAY 1.021277 (-6750 2225);
PAINT ORANGE (-6750 2225);
DISPLAY INVISIBLE (-6750 2225);
FORCEPROP 2 LAST SEC 1
J 0
(-6750 2225);
DISPLAY 0.680851 (-6750 2225);
PAINT MONO (-6750 2225);
DISPLAY INVISIBLE (-6750 2225);
FORCEPROP 1 LAST PATH I92
J 0
(-6750 2175);
DISPLAY 0.978723 (-6750 2175);
PAINT WHITE (-6750 2175);
DISPLAY INVISIBLE (-6750 2175);
FORCEPROP 2 LAST CDS_LIB mstr_discrete
J 0
(-6700 2025);
PAINT ORANGE (-6700 2025);
DISPLAY INVISIBLE (-6700 2025);
FORCEADD RES..1
(-6700 1600);
FORCEPROP 1 LAST PACK_TYPE 0402
J 0
(-6600 1550);
DISPLAY 0.617021 (-6600 1550);
PAINT SKYBLUE (-6600 1550);
FORCEPROP 1 LAST MATERIAL CHIP
J 0
(-6700 1550);
DISPLAY 0.617021 (-6700 1550);
PAINT SKYBLUE (-6700 1550);
FORCEPROP 1 LAST TOLERANCE 5%
J 0
(-6775 1550);
DISPLAY 0.617021 (-6775 1550);
PAINT SKYBLUE (-6775 1550);
FORCEPROP 1 LAST WATTAGE 1/16W
J 2
(-6800 1550);
DISPLAY 0.617021 (-6800 1550);
PAINT SKYBLUE (-6800 1550);
FORCEPROP 1 LASTPIN (-6600 1600) $PN 2
J 0
(-6638 1612);
DISPLAY 0.617021 (-6638 1612);
PAINT ORANGE (-6638 1612);
FORCEPROP 1 LAST PART_NUMBER G21497-005
J 0
(-6850 1700);
DISPLAY 0.617021 (-6850 1700);
PAINT BLUE (-6850 1700);
FORCEPROP 1 LAST LOCATION R1U54
J 0
(-6750 1650);
DISPLAY 0.617021 (-6750 1650);
PAINT AQUA (-6750 1650);
FORCEPROP 1 LASTPIN (-6800 1600) $PN 1
J 0
(-6788 1612);
DISPLAY 0.617021 (-6788 1612);
PAINT ORANGE (-6788 1612);
FORCEPROP 1 LAST VALUE 0.0
J 2
(-6800 1600);
DISPLAY 0.617021 (-6800 1600);
PAINT SKYBLUE (-6800 1600);
FORCEPROP 2 LAST SEC_TYPE 0402
J 0
(-6750 1800);
DISPLAY 1.021277 (-6750 1800);
PAINT ORANGE (-6750 1800);
DISPLAY INVISIBLE (-6750 1800);
FORCEPROP 2 LAST SEC 1
J 0
(-6750 1800);
DISPLAY 0.680851 (-6750 1800);
PAINT MONO (-6750 1800);
DISPLAY INVISIBLE (-6750 1800);
FORCEPROP 1 LAST PATH I93
J 0
(-6750 1750);
DISPLAY 0.978723 (-6750 1750);
PAINT WHITE (-6750 1750);
DISPLAY INVISIBLE (-6750 1750);
FORCEPROP 2 LAST CDS_LIB mstr_discrete
J 0
(-6700 1600);
PAINT ORANGE (-6700 1600);
DISPLAY INVISIBLE (-6700 1600);
FORCEADD RES..1
(-6700 1175);
FORCEPROP 1 LAST WATTAGE 1/16W
J 2
(-6800 1125);
DISPLAY 0.617021 (-6800 1125);
PAINT SKYBLUE (-6800 1125);
FORCEPROP 1 LAST PART_NUMBER G21497-005
J 0
(-6850 1275);
DISPLAY 0.617021 (-6850 1275);
PAINT BLUE (-6850 1275);
FORCEPROP 1 LAST PACK_TYPE 0402
J 0
(-6600 1125);
DISPLAY 0.617021 (-6600 1125);
PAINT SKYBLUE (-6600 1125);
FORCEPROP 1 LAST LOCATION R2U46
J 0
(-6750 1225);
DISPLAY 0.617021 (-6750 1225);
PAINT AQUA (-6750 1225);
FORCEPROP 1 LASTPIN (-6800 1175) $PN 1
J 0
(-6788 1187);
DISPLAY 0.617021 (-6788 1187);
PAINT ORANGE (-6788 1187);
FORCEPROP 1 LAST TOLERANCE 5%
J 0
(-6775 1125);
DISPLAY 0.617021 (-6775 1125);
PAINT SKYBLUE (-6775 1125);
FORCEPROP 1 LASTPIN (-6600 1175) $PN 2
J 0
(-6638 1187);
DISPLAY 0.617021 (-6638 1187);
PAINT ORANGE (-6638 1187);
FORCEPROP 1 LAST MATERIAL CHIP
J 0
(-6700 1125);
DISPLAY 0.617021 (-6700 1125);
PAINT SKYBLUE (-6700 1125);
FORCEPROP 1 LAST VALUE 0.0
J 2
(-6800 1175);
DISPLAY 0.617021 (-6800 1175);
PAINT SKYBLUE (-6800 1175);
FORCEPROP 2 LAST SEC_TYPE 0402
J 0
(-6750 1375);
DISPLAY 1.021277 (-6750 1375);
PAINT ORANGE (-6750 1375);
DISPLAY INVISIBLE (-6750 1375);
FORCEPROP 1 LAST PATH I94
J 0
(-6750 1325);
DISPLAY 0.978723 (-6750 1325);
PAINT WHITE (-6750 1325);
DISPLAY INVISIBLE (-6750 1325);
FORCEPROP 2 LAST SEC 1
J 0
(-6750 1375);
DISPLAY 0.680851 (-6750 1375);
PAINT MONO (-6750 1375);
DISPLAY INVISIBLE (-6750 1375);
FORCEPROP 2 LAST CDS_LIB mstr_discrete
J 0
(-6700 1175);
PAINT ORANGE (-6700 1175);
DISPLAY INVISIBLE (-6700 1175);
FORCEADD RES..1
(-6700 2275);
FORCEPROP 1 LAST PART_NUMBER G21497-005
J 0
(-6850 2375);
DISPLAY 0.617021 (-6850 2375);
PAINT BLUE (-6850 2375);
FORCEPROP 1 LAST PACK_TYPE 0402
J 0
(-6550 2225);
DISPLAY 0.617021 (-6550 2225);
PAINT SKYBLUE (-6550 2225);
FORCEPROP 1 LAST LOCATION R3N30
J 0
(-6750 2325);
DISPLAY 0.617021 (-6750 2325);
PAINT AQUA (-6750 2325);
FORCEPROP 1 LAST MATERIAL EMPTY
J 0
(-6700 2225);
DISPLAY 0.617021 (-6700 2225);
PAINT RED (-6700 2225);
FORCEPROP 1 LASTPIN (-6600 2275) $PN 2
J 0
(-6638 2287);
DISPLAY 0.787234 (-6638 2287);
PAINT ORANGE (-6638 2287);
FORCEPROP 1 LASTPIN (-6800 2275) $PN 1
J 0
(-6788 2287);
DISPLAY 0.787234 (-6788 2287);
PAINT ORANGE (-6788 2287);
FORCEPROP 1 LAST WATTAGE 1/16W
J 2
(-6800 2225);
DISPLAY 0.617021 (-6800 2225);
PAINT SKYBLUE (-6800 2225);
FORCEPROP 1 LAST TOLERANCE 5%
J 0
(-6775 2225);
DISPLAY 0.617021 (-6775 2225);
PAINT SKYBLUE (-6775 2225);
FORCEPROP 1 LAST VALUE 0.0
J 2
(-6800 2275);
DISPLAY 0.617021 (-6800 2275);
PAINT SKYBLUE (-6800 2275);
FORCEPROP 2 LAST SEC_TYPE 0402
J 0
(-6750 2475);
DISPLAY 1.021277 (-6750 2475);
PAINT ORANGE (-6750 2475);
DISPLAY INVISIBLE (-6750 2475);
FORCEPROP 2 LAST SEC 1
J 0
(-6750 2475);
PAINT MONO (-6750 2475);
DISPLAY INVISIBLE (-6750 2475);
FORCEPROP 1 LAST PATH I95
J 0
(-6750 2425);
DISPLAY 0.978723 (-6750 2425);
PAINT WHITE (-6750 2425);
DISPLAY INVISIBLE (-6750 2425);
FORCEPROP 2 LAST CDS_LIB mstr_discrete
J 0
(-6700 2275);
PAINT ORANGE (-6700 2275);
DISPLAY INVISIBLE (-6700 2275);
FORCEADD OFFPAGE..2
(-5250 2275);
FORCEPROP 2 LAST $XR0 121 
J 0
(-5061 2275);
DISPLAY 0.638298 (-5061 2275);
PAINT MONO (-5061 2275);
FORCEPROP 2 LAST CDS_LIB mstr_standard
J 0
(-5250 2275);
PAINT ORANGE (-5250 2275);
DISPLAY INVISIBLE (-5250 2275);
FORCEPROP 2 LAST PATH I96
J 0
(-5075 2350);
DISPLAY 1.021277 (-5075 2350);
PAINT ORANGE (-5075 2350);
DISPLAY INVISIBLE (-5075 2350);
FORCEPROP 1 LAST OFFPAGE TRUE
J 0
(-4925 2150);
DISPLAY 0.872340 (-4925 2150);
PAINT GREEN (-4925 2150);
DISPLAY INVISIBLE (-4925 2150);
FORCEPROP 1 LAST COMMENT_BODY TRUE
J 0
(-5295 2180);
DISPLAY 0.872340 (-5295 2180);
PAINT GREEN (-5295 2180);
DISPLAY INVISIBLE (-5295 2180);
FORCEADD OFFPAGE..2
(-5250 1825);
FORCEPROP 2 LAST $XR0 121 
J 0
(-5061 1825);
DISPLAY 0.638298 (-5061 1825);
PAINT MONO (-5061 1825);
FORCEPROP 2 LAST CDS_LIB mstr_standard
J 0
(-5250 1825);
PAINT ORANGE (-5250 1825);
DISPLAY INVISIBLE (-5250 1825);
FORCEPROP 2 LAST PATH I97
J 0
(-5075 1900);
DISPLAY 1.021277 (-5075 1900);
PAINT ORANGE (-5075 1900);
DISPLAY INVISIBLE (-5075 1900);
FORCEPROP 1 LAST OFFPAGE TRUE
J 0
(-4925 1700);
DISPLAY 0.872340 (-4925 1700);
PAINT GREEN (-4925 1700);
DISPLAY INVISIBLE (-4925 1700);
FORCEPROP 1 LAST COMMENT_BODY TRUE
J 0
(-5295 1730);
DISPLAY 0.872340 (-5295 1730);
PAINT GREEN (-5295 1730);
DISPLAY INVISIBLE (-5295 1730);
FORCEADD RES..1
(-6700 1825);
FORCEPROP 1 LAST PACK_TYPE 0402
J 0
(-6550 1775);
DISPLAY 0.617021 (-6550 1775);
PAINT SKYBLUE (-6550 1775);
FORCEPROP 1 LAST MATERIAL EMPTY
J 0
(-6700 1775);
DISPLAY 0.617021 (-6700 1775);
PAINT RED (-6700 1775);
FORCEPROP 1 LAST TOLERANCE 5%
J 0
(-6775 1775);
DISPLAY 0.617021 (-6775 1775);
PAINT SKYBLUE (-6775 1775);
FORCEPROP 1 LAST WATTAGE 1/16W
J 2
(-6800 1775);
DISPLAY 0.617021 (-6800 1775);
PAINT SKYBLUE (-6800 1775);
FORCEPROP 1 LASTPIN (-6800 1825) $PN 1
J 0
(-6788 1837);
DISPLAY 0.787234 (-6788 1837);
PAINT ORANGE (-6788 1837);
FORCEPROP 1 LASTPIN (-6600 1825) $PN 2
J 0
(-6638 1837);
DISPLAY 0.787234 (-6638 1837);
PAINT ORANGE (-6638 1837);
FORCEPROP 1 LAST LOCATION R9G30
J 0
(-6750 1875);
DISPLAY 0.617021 (-6750 1875);
PAINT AQUA (-6750 1875);
FORCEPROP 1 LAST PART_NUMBER G21497-005
J 0
(-6850 1925);
DISPLAY 0.617021 (-6850 1925);
PAINT BLUE (-6850 1925);
FORCEPROP 1 LAST VALUE 0.0
J 2
(-6800 1825);
DISPLAY 0.617021 (-6800 1825);
PAINT SKYBLUE (-6800 1825);
FORCEPROP 2 LAST SEC_TYPE 0402
J 0
(-6750 2025);
DISPLAY 1.021277 (-6750 2025);
PAINT ORANGE (-6750 2025);
DISPLAY INVISIBLE (-6750 2025);
FORCEPROP 2 LAST SEC 1
J 0
(-6750 2025);
PAINT MONO (-6750 2025);
DISPLAY INVISIBLE (-6750 2025);
FORCEPROP 1 LAST PATH I98
J 0
(-6750 1975);
DISPLAY 0.978723 (-6750 1975);
PAINT WHITE (-6750 1975);
DISPLAY INVISIBLE (-6750 1975);
FORCEPROP 2 LAST CDS_LIB mstr_discrete
J 0
(-6700 1825);
PAINT ORANGE (-6700 1825);
DISPLAY INVISIBLE (-6700 1825);
FORCEADD OFFPAGE..2
(-5250 1400);
FORCEPROP 2 LAST $XR0 121 
J 0
(-5061 1400);
DISPLAY 0.638298 (-5061 1400);
PAINT MONO (-5061 1400);
FORCEPROP 2 LAST CDS_LIB mstr_standard
J 0
(-5250 1400);
PAINT ORANGE (-5250 1400);
DISPLAY INVISIBLE (-5250 1400);
FORCEPROP 2 LAST PATH I99
J 0
(-5075 1475);
DISPLAY 1.021277 (-5075 1475);
PAINT ORANGE (-5075 1475);
DISPLAY INVISIBLE (-5075 1475);
FORCEPROP 1 LAST OFFPAGE TRUE
J 0
(-4925 1275);
DISPLAY 0.872340 (-4925 1275);
PAINT GREEN (-4925 1275);
DISPLAY INVISIBLE (-4925 1275);
FORCEPROP 1 LAST COMMENT_BODY TRUE
J 0
(-5295 1305);
DISPLAY 0.872340 (-5295 1305);
PAINT GREEN (-5295 1305);
DISPLAY INVISIBLE (-5295 1305);
FORCEADD DESIGN_NOTE..1
(-4275 2450);
FORCEPROP 1 LAST COMMENT_BODY TRUE
J 0
(-4250 2550);
DISPLAY 0.978723 (-4250 2550);
PAINT ORANGE (-4250 2550);
DISPLAY INVISIBLE (-4250 2550);
FORCEPROP 2 LAST CDS_LIB mstr_symbols
J 0
(-4275 2450);
PAINT ORANGE (-4275 2450);
DISPLAY INVISIBLE (-4275 2450);
FORCEADD DNS..2
(-7170 4520);
PAINT RED (-7170 4520);
FORCEPROP 2 LAST CDS_LIB mstr_misc
J 0
(-7170 4520);
PAINT ORANGE (-7170 4520);
DISPLAY INVISIBLE (-7170 4520);
FORCEPROP 1 LAST COMMENT_BODY TRUE
R 1
J 0
(-7095 4295);
DISPLAY 0.872340 (-7095 4295);
PAINT GREEN (-7095 4295);
DISPLAY INVISIBLE (-7095 4295);
FORCEADD DNS..2
(-2845 4595);
PAINT RED (-2845 4595);
FORCEPROP 2 LAST CDS_LIB mstr_misc
J 0
(-2845 4595);
PAINT ORANGE (-2845 4595);
DISPLAY INVISIBLE (-2845 4595);
FORCEPROP 1 LAST COMMENT_BODY TRUE
R 1
J 0
(-2770 4370);
DISPLAY 0.872340 (-2770 4370);
PAINT GREEN (-2770 4370);
DISPLAY INVISIBLE (-2770 4370);
FORCEADD DNS..2
(-3095 2070);
PAINT RED (-3095 2070);
FORCEPROP 1 LAST COMMENT_BODY TRUE
R 1
J 0
(-3020 1845);
DISPLAY 0.872340 (-3020 1845);
PAINT GREEN (-3020 1845);
DISPLAY INVISIBLE (-3020 1845);
FORCEPROP 2 LAST CDS_LIB mstr_misc
J 0
(-3095 2070);
PAINT ORANGE (-3095 2070);
DISPLAY INVISIBLE (-3095 2070);
FORCEADD DNS..2
(-6695 1820);
PAINT RED (-6695 1820);
FORCEPROP 2 LAST CDS_LIB mstr_misc
J 0
(-6695 1820);
PAINT ORANGE (-6695 1820);
DISPLAY INVISIBLE (-6695 1820);
FORCEPROP 1 LAST COMMENT_BODY TRUE
R 1
J 0
(-6620 1595);
DISPLAY 0.872340 (-6620 1595);
PAINT GREEN (-6620 1595);
DISPLAY INVISIBLE (-6620 1595);
FORCEADD DNS..2
(-6695 2270);
PAINT RED (-6695 2270);
FORCEPROP 2 LAST CDS_LIB mstr_misc
J 0
(-6695 2270);
PAINT ORANGE (-6695 2270);
DISPLAY INVISIBLE (-6695 2270);
FORCEPROP 1 LAST COMMENT_BODY TRUE
R 1
J 0
(-6620 2045);
DISPLAY 0.872340 (-6620 2045);
PAINT GREEN (-6620 2045);
DISPLAY INVISIBLE (-6620 2045);
FORCEADD DNS..2
(-6695 1395);
PAINT RED (-6695 1395);
FORCEPROP 2 LAST CDS_LIB mstr_misc
J 0
(-6695 1395);
PAINT ORANGE (-6695 1395);
DISPLAY INVISIBLE (-6695 1395);
FORCEPROP 1 LAST COMMENT_BODY TRUE
R 1
J 0
(-6620 1170);
DISPLAY 0.872340 (-6620 1170);
PAINT GREEN (-6620 1170);
DISPLAY INVISIBLE (-6620 1170);
FORCEADD DNS..2
(-7445 3495);
PAINT RED (-7445 3495);
FORCEPROP 2 LAST CDS_LIB mstr_misc
J 0
(-7445 3495);
PAINT ORANGE (-7445 3495);
DISPLAY INVISIBLE (-7445 3495);
FORCEPROP 1 LAST COMMENT_BODY TRUE
R 1
J 0
(-7370 3270);
DISPLAY 0.872340 (-7370 3270);
PAINT GREEN (-7370 3270);
DISPLAY INVISIBLE (-7370 3270);
FORCEADD CAD_NOTE..1
(-4000 3675);
FORCEPROP 0 LAST L2 STEERING RESISTORS
J 0
(-4150 3525);
DISPLAY 0.638298 (-4150 3525);
PAINT ORANGE (-4150 3525);
FORCEPROP 0 LAST L1 USE SHARED PADS FOR 0OHM
J 0
(-4150 3575);
DISPLAY 0.617021 (-4150 3575);
PAINT WHITE (-4150 3575);
FORCEPROP 2 LAST CDS_LIB mstr_symbols
J 0
(-4000 3675);
PAINT ORANGE (-4000 3675);
DISPLAY INVISIBLE (-4000 3675);
FORCEPROP 1 LAST COMMENT_BODY TRUE
J 0
(-3975 3775);
DISPLAY 1.319149 (-3975 3775);
PAINT WHITE (-3975 3775);
DISPLAY INVISIBLE (-3975 3775);
FORCEADD CAD_NOTE..1
(-8675 2700);
FORCEPROP 0 LAST L2 CORRESPONDING CPU
J 0
(-8825 2550);
DISPLAY 0.638298 (-8825 2550);
PAINT ORANGE (-8825 2550);
FORCEPROP 0 LAST L1 PLACE PU RESISTORS NEAR
J 0
(-8825 2600);
DISPLAY 0.617021 (-8825 2600);
PAINT WHITE (-8825 2600);
FORCEPROP 2 LAST CDS_LIB mstr_symbols
J 0
(-8675 2700);
PAINT MONO (-8675 2700);
DISPLAY INVISIBLE (-8675 2700);
FORCEPROP 1 LAST COMMENT_BODY TRUE
J 0
(-8650 2800);
DISPLAY 1.319149 (-8650 2800);
PAINT WHITE (-8650 2800);
DISPLAY INVISIBLE (-8650 2800);
FORCEADD DNS..2
(-6695 970);
PAINT RED (-6695 970);
FORCEPROP 2 LAST CDS_LIB mstr_misc
J 0
(-6695 970);
PAINT ORANGE (-6695 970);
DISPLAY INVISIBLE (-6695 970);
FORCEPROP 1 LAST COMMENT_BODY TRUE
R 1
J 0
(-6620 745);
DISPLAY 0.872340 (-6620 745);
PAINT GREEN (-6620 745);
DISPLAY INVISIBLE (-6620 745);
FORCEADD CAD_NOTE..1
(-6400 3425);
FORCEPROP 0 LAST L2 STEERING RESISTORS
J 0
(-6550 3275);
DISPLAY 0.638298 (-6550 3275);
PAINT ORANGE (-6550 3275);
FORCEPROP 0 LAST L1 USE SHARED PADS FOR 0OHM
J 0
(-6550 3325);
DISPLAY 0.617021 (-6550 3325);
PAINT WHITE (-6550 3325);
FORCEPROP 2 LAST CDS_LIB mstr_symbols
J 0
(-6400 3425);
PAINT ORANGE (-6400 3425);
DISPLAY INVISIBLE (-6400 3425);
FORCEPROP 1 LAST COMMENT_BODY TRUE
J 0
(-6375 3525);
DISPLAY 1.319149 (-6375 3525);
PAINT WHITE (-6375 3525);
DISPLAY INVISIBLE (-6375 3525);
FORCEADD DNS..2
(-7170 3495);
PAINT RED (-7170 3495);
FORCEPROP 2 LAST CDS_LIB mstr_misc
J 0
(-7170 3495);
PAINT ORANGE (-7170 3495);
DISPLAY INVISIBLE (-7170 3495);
FORCEPROP 1 LAST COMMENT_BODY TRUE
R 1
J 0
(-7095 3270);
DISPLAY 0.872340 (-7095 3270);
PAINT GREEN (-7095 3270);
DISPLAY INVISIBLE (-7095 3270);
FORCEADD DNS..2
(-2870 3420);
PAINT RED (-2870 3420);
FORCEPROP 2 LAST CDS_LIB mstr_misc
J 0
(-2870 3420);
PAINT ORANGE (-2870 3420);
DISPLAY INVISIBLE (-2870 3420);
FORCEPROP 1 LAST COMMENT_BODY TRUE
R 1
J 0
(-2795 3195);
DISPLAY 0.872340 (-2795 3195);
PAINT GREEN (-2795 3195);
DISPLAY INVISIBLE (-2795 3195);
FORCEADD DNS..2
(-3170 3420);
PAINT RED (-3170 3420);
FORCEPROP 2 LAST CDS_LIB mstr_misc
J 0
(-3170 3420);
PAINT ORANGE (-3170 3420);
DISPLAY INVISIBLE (-3170 3420);
FORCEPROP 1 LAST COMMENT_BODY TRUE
R 1
J 0
(-3095 3195);
DISPLAY 0.872340 (-3095 3195);
PAINT GREEN (-3095 3195);
DISPLAY INVISIBLE (-3095 3195);
FORCEADD DNS..2
(-3145 4595);
PAINT RED (-3145 4595);
FORCEPROP 2 LAST CDS_LIB mstr_misc
J 0
(-3145 4595);
PAINT ORANGE (-3145 4595);
DISPLAY INVISIBLE (-3145 4595);
FORCEPROP 1 LAST COMMENT_BODY TRUE
R 1
J 0
(-3070 4370);
DISPLAY 0.872340 (-3070 4370);
PAINT GREEN (-3070 4370);
DISPLAY INVISIBLE (-3070 4370);
FORCEADD CAD_NOTE..1
(-6725 725);
FORCEPROP 0 LAST L1 USE SHARED PADS WITH
J 0
(-6875 625);
DISPLAY 0.617021 (-6875 625);
PAINT WHITE (-6875 625);
FORCEPROP 0 LAST L2 33.2OHM RESISTORS
J 0
(-6875 575);
DISPLAY 0.638298 (-6875 575);
PAINT ORANGE (-6875 575);
FORCEPROP 2 LAST CDS_LIB mstr_symbols
J 0
(-6725 725);
PAINT ORANGE (-6725 725);
DISPLAY INVISIBLE (-6725 725);
FORCEPROP 1 LAST COMMENT_BODY TRUE
J 0
(-6700 825);
DISPLAY 1.319149 (-6700 825);
PAINT WHITE (-6700 825);
DISPLAY INVISIBLE (-6700 825);
FORCEADD CAD_NOTE..1
(-8325 5175);
FORCEPROP 0 LAST L1 PLACE PU RESISTORS NEAR GTL2014
J 0
(-8475 5075);
DISPLAY 0.617021 (-8475 5075);
PAINT WHITE (-8475 5075);
FORCEPROP 2 LAST CDS_LIB mstr_symbols
J 0
(-8325 5175);
PAINT MONO (-8325 5175);
DISPLAY INVISIBLE (-8325 5175);
FORCEPROP 1 LAST COMMENT_BODY TRUE
J 0
(-8300 5275);
DISPLAY 1.319149 (-8300 5275);
PAINT WHITE (-8300 5275);
DISPLAY INVISIBLE (-8300 5275);
FORCEADD CAD_NOTE..1
(-2375 3550);
FORCEPROP 0 LAST L2 STEERING RESISTORS
J 0
(-2525 3400);
DISPLAY 0.638298 (-2525 3400);
PAINT ORANGE (-2525 3400);
FORCEPROP 0 LAST L1 USE SHARED PADS WITH 0OHM
J 0
(-2525 3450);
DISPLAY 0.617021 (-2525 3450);
PAINT WHITE (-2525 3450);
FORCEPROP 2 LAST CDS_LIB mstr_symbols
J 0
(-2375 3550);
PAINT ORANGE (-2375 3550);
DISPLAY INVISIBLE (-2375 3550);
FORCEPROP 1 LAST COMMENT_BODY TRUE
J 0
(-2350 3650);
DISPLAY 1.319149 (-2350 3650);
PAINT WHITE (-2350 3650);
DISPLAY INVISIBLE (-2350 3650);
FORCEADD DNS..2
(-7445 4520);
PAINT RED (-7445 4520);
FORCEPROP 2 LAST CDS_LIB mstr_misc
J 0
(-7445 4520);
PAINT ORANGE (-7445 4520);
DISPLAY INVISIBLE (-7445 4520);
FORCEPROP 1 LAST COMMENT_BODY TRUE
R 1
J 0
(-7370 4295);
DISPLAY 0.872340 (-7370 4295);
PAINT GREEN (-7370 4295);
DISPLAY INVISIBLE (-7370 4295);
FORCEADD INTEL_CORP_BPAGE..1
(-1075 450);
FORCEPROP 1 LAST CDS_CON_LAST_MODIFIED Fri Jun 16 17:48:57 2017
J 0
(-2500 775);
DISPLAY 1.361702 (-2500 775);
PAINT GREEN (-2500 775);
DISPLAY INVISIBLE (-2500 775);
FORCEPROP 1 LAST CUSTOM_TXT_CDS <CURRENT_DESIGN_SHEET> OF <TOTAL_DESIGN_SHEETS>
J 0
(-1575 475);
PAINT ORANGE (-1575 475);
FORCEPROP 1 LAST CUSTOM_TXT_CDS <CON_LAST_MODIFIED>
J 0
(-5075 550);
PAINT ORANGE (-5075 550);
FORCEPROP 2 LAST CUSTOM_TXT_CDS <XR_PAGE_TITLE>
J 0
(-8965 5700);
DISPLAY 0.638298 (-8965 5700);
PAINT PINK (-8965 5700);
DISPLAY INVISIBLE (-8965 5700);
FORCEPROP 1 LAST SCH_TITLE MEMHOT LVT3 LEVEL TRANSLATION
J 0
(-9025 500);
DISPLAY 1.212766 (-9025 500);
PAINT ORANGE (-9025 500);
FORCEPROP 2 LAST PAGE_BORDER TRUE
J 0
(-8965 5700);
DISPLAY 0.851064 (-8965 5700);
PAINT PINK (-8965 5700);
DISPLAY INVISIBLE (-8965 5700);
FORCEPROP 2 LAST CDS_LIB mstr_symbols
J 0
(-1075 450);
DISPLAY 1.361702 (-1075 450);
PAINT ORANGE (-1075 450);
DISPLAY INVISIBLE (-1075 450);
FORCEPROP 1 LAST COMMENT_BODY TRUE
J 0
(-1063 462);
DISPLAY 0.617021 (-1063 462);
PAINT GREEN (-1063 462);
DISPLAY INVISIBLE (-1063 462);
FORCEPROP 2 LAST CDS_XR_PAGE_TITLE CR-152 : @BASEBOARD_FAB2_LIB.BASEBOARD_FAB2(SCH_1):PAGE152
J 0
(-8965 5700);
DISPLAY 0.638298 (-8965 5700);
PAINT PINK (-8965 5700);
DISPLAY INVISIBLE (-8965 5700);
FORCEADD DESIGN_NOTE..1
(-5575 3450);
PAINT PURPLE (-5575 3450);
FORCEPROP 0 LAST L1 THE GTL2014 IS BEING USED AS GTL TO LVTTL CONVERTER, SO
J 0
(-5775 3325);
DISPLAY 0.808511 (-5775 3325);
PAINT VIOLET (-5775 3325);
FORCEPROP 0 LAST L2 THE PINS 'BX' ARE INPUTS & 'AX' OUTPUTS ARE PUSH-PULL.
J 0
(-5775 3275);
DISPLAY 0.808511 (-5775 3275);
PAINT VIOLET (-5775 3275);
FORCEPROP 0 LAST L3 VREF IS SET AT 2/3 OF VCCIO
J 0
(-5775 3225);
DISPLAY 0.808511 (-5775 3225);
PAINT VIOLET (-5775 3225);
FORCEPROP 2 LAST CDS_LIB mstr_symbols
J 0
(-5575 3450);
PAINT ORANGE (-5575 3450);
DISPLAY INVISIBLE (-5575 3450);
FORCEPROP 1 LAST COMMENT_BODY TRUE
J 0
(-5550 3550);
DISPLAY 1.319149 (-5550 3550);
PAINT GREEN (-5550 3550);
DISPLAY INVISIBLE (-5550 3550);
WIRE 16 -1 (-2550 2200)(-2550 2250);
WIRE 16 -1 (-3100 2250)(-3100 2175);
WIRE 16 -1 (-5900 3575)(-5900 3650);
WIRE 16 -1 (-5900 3650)(-5900 3700);
WIRE 16 -1 (-5900 3650)(-5850 3650);
WIRE 16 -1 (-5900 3700)(-5900 3750);
WIRE 16 -1 (-5900 3700)(-5850 3700);
WIRE 16 -1 (-5900 3750)(-5850 3750);
WIRE 16 -1 (-4525 4500)(-4525 4550);
WIRE 16 -1 (-2550 1325)(-2550 1375);
WIRE 16 -1 (-2925 1375)(-2550 1375);
WIRE 16 -1 (-2550 1375)(-2550 1500);
WIRE 16 -1 (-2925 1500)(-2925 1375);
WIRE 16 -1 (-3825 4175)(-3825 4200);
WIRE 16 -1 (-3825 4200)(-4250 4200);
WIRE 16 -1 (-4775 4875)(-4775 4825);
WIRE 16 -1 (-4525 4825)(-4775 4825);
WIRE 16 -1 (-4775 4825)(-4775 4350);
WIRE 16 -1 (-4775 4350)(-4950 4350);
WIRE 16 -1 (-4525 4750)(-4525 4825);
WIRE 16 -1 (-7925 4825)(-7925 4900);
WIRE 16 -1 (-7875 4825)(-7925 4825);
WIRE 16 -1 (-7925 4825)(-7975 4825);
WIRE 16 -1 (-7975 4825)(-7975 4750);
WIRE 16 -1 (-7875 4750)(-7875 4825);
WIRE 16 -1 (-8375 4825)(-8375 4900);
WIRE 16 -1 (-8375 4825)(-8425 4825);
WIRE 16 -1 (-8375 4825)(-8325 4825);
WIRE 16 -1 (-8325 4750)(-8325 4825);
WIRE 16 -1 (-8425 4825)(-8425 4750);
WIRE 16 -1 (-7850 3025)(-7850 2975);
WIRE 16 -1 (-7850 3025)(-7800 3025);
WIRE 16 -1 (-7900 3025)(-7850 3025);
WIRE 16 -1 (-7900 3150)(-7900 3025);
WIRE 16 -1 (-7800 3025)(-7800 3150);
WIRE 16 -1 (-8300 2975)(-8300 3025);
WIRE 16 -1 (-8300 3025)(-8250 3025);
WIRE 16 -1 (-8350 3025)(-8300 3025);
WIRE 16 -1 (-8350 3175)(-8350 3025);
WIRE 16 -1 (-8250 3025)(-8250 3175);
WIRE 16 2175 (-8675 5050)(-8675 4400);
WIRE 16 2175 (-7600 5050)(-8675 5050);
WIRE 16 2175 (-8675 4400)(-7600 4400);
WIRE 16 2175 (-7600 4400)(-7600 5050);
WIRE 16 -1 (-6800 1400)(-7050 1400);
WIRE 16 -1 (-7050 1400)(-7050 1600);
WIRE 16 -1 (-7050 1600)(-6800 1600);
WIRE 16 -1 (-7950 1600)(-7050 1600);
FORCEPROP 2 LAST SIG_NAME H_CPU1_MEMGHJ_MEMHOT_LVT3_N
J 0
(-7910 1610);
DISPLAY 0.617021 (-7910 1610);
PAINT ORANGE (-7910 1610);
WIRE 16 -1 (-3150 5075)(-3150 4700);
WIRE 16 -1 (-7175 5075)(-3150 5075);
FORCEPROP 2 LAST SIG_NAME H_CPU0_MEMDEF_MEMHOT_G_PCH_N
J 0
(-5860 5085);
DISPLAY 0.617021 (-5860 5085);
PAINT ORANGE (-5860 5085);
FORCEPROP 2 LASTPROP $XRERR UNIQUE?
J 0
(-6100 5085);
DISPLAY 0.638298 (-6100 5085);
PAINT MONO (-6100 5085);
DISPLAY INVISIBLE (-6100 5085);
WIRE 16 -1 (-7175 4625)(-7175 5075);
WIRE 16 -1 (-2875 3050)(-2875 3325);
WIRE 16 -1 (-7450 3400)(-7450 3050);
WIRE 16 -1 (-7450 3050)(-2875 3050);
FORCEPROP 2 LAST SIG_NAME H_CPU1_MEMKLM_MEMHOT_G_PCH_N
J 0
(-5760 3060);
DISPLAY 0.617021 (-5760 3060);
PAINT ORANGE (-5760 3060);
FORCEPROP 2 LASTPROP $XRERR UNIQUE?
J 0
(-6000 3060);
DISPLAY 0.638298 (-6000 3060);
PAINT MONO (-6000 3060);
DISPLAY INVISIBLE (-6000 3060);
WIRE 16 -1 (-7175 3400)(-7175 3100);
WIRE 16 -1 (-7175 3100)(-3175 3100);
FORCEPROP 2 LAST SIG_NAME H_CPU1_MEMGHJ_MEMHOT_G_PCH_N
J 0
(-5760 3110);
DISPLAY 0.617021 (-5760 3110);
PAINT ORANGE (-5760 3110);
FORCEPROP 2 LASTPROP $XRERR UNIQUE?
J 0
(-6000 3110);
DISPLAY 0.638298 (-6000 3110);
PAINT MONO (-6000 3110);
DISPLAY INVISIBLE (-6000 3110);
WIRE 16 -1 (-3175 3100)(-3175 3325);
WIRE 16 -1 (-3425 1800)(-2925 1800);
FORCEPROP 2 LAST SIG_NAME P0V7_GTL2014_2
J 0
(-3360 1810);
DISPLAY 0.617021 (-3360 1810);
PAINT ORANGE (-3360 1810);
WIRE 16 -1 (-2925 1700)(-2925 1800);
WIRE 16 -1 (-2925 1800)(-2550 1800);
FORCEPROP 0 LAST VOLTAGE +0.7
J 0
(-2725 1850);
DISPLAY 1.021277 (-2725 1850);
PAINT SKYBLUE (-2725 1850);
DISPLAY INVISIBLE (-2725 1850);
WIRE 16 -1 (-2550 1800)(-2550 1700);
WIRE 16 -1 (-2550 1850)(-2550 1800);
WIRE 16 -1 (-2550 1950)(-2550 1850);
WIRE 16 -1 (-3100 1975)(-3100 1850);
WIRE 16 -1 (-3100 1850)(-2550 1850);
WIRE 3 682 (-2650 2400)(-2650 1900);
WIRE 3 682 (-2250 2400)(-2650 2400);
WIRE 3 682 (-2650 1900)(-2250 1900);
WIRE 3 682 (-2250 1900)(-2250 2400);
WIRE 16 -1 (-6850 3750)(-6700 3750);
WIRE 16 -1 (-6700 3900)(-6700 3750);
WIRE 16 -1 (-5850 3900)(-6700 3900);
FORCEPROP 2 LAST SIG_NAME H_CPU1_MEMKLM_MEMHOT_G_R_N
J 0
(-6610 3910);
DISPLAY 0.617021 (-6610 3910);
PAINT ORANGE (-6610 3910);
FORCEPROP 2 LASTPROP $XRERR UNIQUE?
J 0
(-6850 3910);
DISPLAY 0.638298 (-6850 3910);
PAINT MONO (-6850 3910);
DISPLAY INVISIBLE (-6850 3910);
WIRE 16 -1 (-6850 3900)(-6750 3900);
WIRE 16 -1 (-6750 3950)(-6750 3900);
WIRE 16 -1 (-5850 3950)(-6750 3950);
FORCEPROP 2 LAST SIG_NAME H_CPU1_MEMGHJ_MEMHOT_G_R_N
J 0
(-6610 3960);
DISPLAY 0.617021 (-6610 3960);
PAINT ORANGE (-6610 3960);
FORCEPROP 2 LASTPROP $XRERR UNIQUE?
J 0
(-6850 3960);
DISPLAY 0.638298 (-6850 3960);
PAINT MONO (-6850 3960);
DISPLAY INVISIBLE (-6850 3960);
WIRE 16 -1 (-6850 4050)(-6750 4050);
WIRE 16 -1 (-6750 4000)(-6750 4050);
WIRE 16 -1 (-5850 4000)(-6750 4000);
FORCEPROP 2 LAST SIG_NAME H_CPU0_MEMDEF_MEMHOT_G_R_N
J 0
(-6610 4010);
DISPLAY 0.617021 (-6610 4010);
PAINT ORANGE (-6610 4010);
FORCEPROP 2 LASTPROP $XRERR UNIQUE?
J 0
(-6850 4010);
DISPLAY 0.638298 (-6850 4010);
PAINT MONO (-6850 4010);
DISPLAY INVISIBLE (-6850 4010);
WIRE 16 -1 (-6850 4225)(-6700 4225);
WIRE 16 -1 (-6700 4050)(-6700 4225);
WIRE 16 -1 (-5850 4050)(-6700 4050);
FORCEPROP 2 LAST SIG_NAME H_CPU0_MEMABC_MEMHOT_G_R_N
J 0
(-6610 4060);
DISPLAY 0.617021 (-6610 4060);
PAINT ORANGE (-6610 4060);
FORCEPROP 2 LASTPROP $XRERR UNIQUE?
J 0
(-6850 4060);
DISPLAY 0.638298 (-6850 4060);
PAINT MONO (-6850 4060);
DISPLAY INVISIBLE (-6850 4060);
WIRE 16 -1 (-7450 4425)(-7450 4225);
WIRE 16 -1 (-7050 4225)(-7450 4225);
WIRE 16 -1 (-7800 3350)(-7800 4225);
WIRE 16 -1 (-7450 4225)(-7800 4225);
WIRE 16 -1 (-7875 4225)(-7800 4225);
WIRE 16 -1 (-7875 4550)(-7875 4225);
WIRE 16 -1 (-8475 4225)(-7875 4225);
FORCEPROP 2 LAST SIG_NAME H_CPU0_MEMABC_MEMHOT_G_N
J 0
(-8460 4235);
DISPLAY 0.617021 (-8460 4235);
PAINT ORANGE (-8460 4235);
WIRE 16 -1 (-7050 4050)(-7175 4050);
WIRE 16 -1 (-7175 4425)(-7175 4050);
WIRE 16 -1 (-7900 3350)(-7900 4050);
WIRE 16 -1 (-7175 4050)(-7900 4050);
WIRE 16 -1 (-7975 4050)(-8475 4050);
FORCEPROP 2 LAST SIG_NAME H_CPU0_MEMDEF_MEMHOT_G_N
J 0
(-8460 4060);
DISPLAY 0.617021 (-8460 4060);
PAINT ORANGE (-8460 4060);
WIRE 16 -1 (-7975 4050)(-7900 4050);
WIRE 16 -1 (-7975 4550)(-7975 4050);
WIRE 16 -1 (-4950 4300)(-4150 4300);
FORCEPROP 2 LAST SIG_NAME P0V7_GTL2014_2
J 0
(-4885 4310);
DISPLAY 0.617021 (-4885 4310);
PAINT ORANGE (-4885 4310);
WIRE 16 -1 (-4450 4200)(-4950 4200);
FORCEPROP 2 LAST SIG_NAME PD_DIR_2
J 0
(-4860 4210);
DISPLAY 0.617021 (-4860 4210);
PAINT ORANGE (-4860 4210);
FORCEPROP 2 LASTPROP $XRERR UNIQUE?
J 0
(-5100 4210);
DISPLAY 0.638298 (-5100 4210);
PAINT MONO (-5100 4210);
DISPLAY INVISIBLE (-5100 4210);
WIRE 16 2175 (-8625 2800)(-8625 3475);
WIRE 16 2175 (-7600 2800)(-8625 2800);
WIRE 16 2175 (-8625 3475)(-7600 3475);
WIRE 16 2175 (-7600 3475)(-7600 2800);
WIRE 16 -1 (-6800 2275)(-7025 2275);
WIRE 16 -1 (-7025 2275)(-7025 2475);
WIRE 16 -1 (-7025 2475)(-6800 2475);
WIRE 16 -1 (-7950 2475)(-7025 2475);
FORCEPROP 2 LAST SIG_NAME H_CPU0_MEMABC_MEMHOT_LVT3_N
J 0
(-7910 2485);
DISPLAY 0.617021 (-7910 2485);
PAINT ORANGE (-7910 2485);
WIRE 16 2175 (-6425 825)(-6925 825);
WIRE 16 2175 (-6425 2650)(-6425 825);
WIRE 16 2175 (-6925 825)(-6925 2650);
WIRE 16 2175 (-6925 2650)(-6425 2650);
WIRE 16 -1 (-6600 2275)(-5300 2275);
FORCEPROP 2 LAST SIG_NAME H_CPU0_MEMABC_MEMHOT_PCH_N
J 0
(-6375 2285);
DISPLAY 0.617021 (-6375 2285);
PAINT ORANGE (-6375 2285);
WIRE 16 -1 (-6600 2025)(-5300 2025);
FORCEPROP 2 LAST SIG_NAME H_CPU0_MEMDEF_MEMHOT_LVT3_BMC_N
J 0
(-6375 2035);
DISPLAY 0.617021 (-6375 2035);
PAINT ORANGE (-6375 2035);
WIRE 16 -1 (-6600 1825)(-5300 1825);
FORCEPROP 2 LAST SIG_NAME H_CPU0_MEMDEF_MEMHOT_PCH_N
J 0
(-6375 1835);
DISPLAY 0.617021 (-6375 1835);
PAINT ORANGE (-6375 1835);
WIRE 16 -1 (-6600 1175)(-5300 1175);
FORCEPROP 2 LAST SIG_NAME H_CPU1_MEMKLM_MEMHOT_LVT3_BMC_N
J 0
(-6375 1185);
DISPLAY 0.617021 (-6375 1185);
PAINT ORANGE (-6375 1185);
WIRE 16 -1 (-6600 1600)(-5300 1600);
FORCEPROP 2 LAST SIG_NAME H_CPU1_MEMGHJ_MEMHOT_LVT3_BMC_N
J 0
(-6375 1610);
DISPLAY 0.617021 (-6375 1610);
PAINT ORANGE (-6375 1610);
WIRE 16 -1 (-6600 1400)(-5300 1400);
FORCEPROP 2 LAST SIG_NAME H_CPU1_MEMGHJ_MEMHOT_PCH_N
J 0
(-6375 1410);
DISPLAY 0.617021 (-6375 1410);
PAINT ORANGE (-6375 1410);
WIRE 16 -1 (-6800 975)(-7050 975);
WIRE 16 -1 (-7050 975)(-7050 1175);
WIRE 16 -1 (-7050 1175)(-6800 1175);
WIRE 16 -1 (-7950 1175)(-7050 1175);
FORCEPROP 2 LAST SIG_NAME H_CPU1_MEMKLM_MEMHOT_LVT3_N
J 0
(-7910 1185);
DISPLAY 0.617021 (-7910 1185);
PAINT ORANGE (-7910 1185);
WIRE 16 -1 (-6600 2475)(-5300 2475);
FORCEPROP 2 LAST SIG_NAME H_CPU0_MEMABC_MEMHOT_LVT3_BMC_N
J 0
(-6375 2485);
DISPLAY 0.617021 (-6375 2485);
PAINT ORANGE (-6375 2485);
WIRE 16 -1 (-3525 4075)(-3475 4075);
WIRE 16 -1 (-3525 4000)(-3525 4075);
WIRE 16 -1 (-4950 4000)(-3525 4000);
FORCEPROP 2 LAST SIG_NAME H_CPU0_DEF_MEMHOT_LVT3_R_N
J 0
(-4860 4010);
DISPLAY 0.617021 (-4860 4010);
PAINT ORANGE (-4860 4010);
FORCEPROP 2 LASTPROP $XRERR UNIQUE?
J 0
(-5100 4010);
DISPLAY 0.638298 (-5100 4010);
PAINT MONO (-5100 4010);
DISPLAY INVISIBLE (-5100 4010);
WIRE 16 -1 (-3600 3725)(-3475 3725);
WIRE 16 -1 (-3600 3900)(-3600 3725);
WIRE 16 -1 (-4950 3900)(-3600 3900);
FORCEPROP 2 LAST SIG_NAME H_CPU1_KLM_MEMHOT_LVT3_R_N
J 0
(-4860 3910);
DISPLAY 0.617021 (-4860 3910);
PAINT ORANGE (-4860 3910);
FORCEPROP 2 LASTPROP $XRERR UNIQUE?
J 0
(-5100 3910);
DISPLAY 0.638298 (-5100 3910);
PAINT MONO (-5100 3910);
DISPLAY INVISIBLE (-5100 3910);
WIRE 16 -1 (-3175 3900)(-3175 3525);
WIRE 16 -1 (-3175 3900)(-2500 3900);
WIRE 16 -1 (-3275 3900)(-3175 3900);
FORCEPROP 2 LAST SIG_NAME H_CPU1_MEMGHJ_MEMHOT_LVT3_K_N
J 0
(-3250 3910);
DISPLAY 0.617021 (-3250 3910);
PAINT ORANGE (-3250 3910);
FORCEPROP 2 LASTPROP $XRERR UNIQUE?
J 0
(-3490 3910);
DISPLAY 0.638298 (-3490 3910);
PAINT MONO (-3490 3910);
DISPLAY INVISIBLE (-3490 3910);
WIRE 16 2175 (-2200 3625)(-2600 3625);
WIRE 16 2175 (-2200 4375)(-2200 3625);
WIRE 16 2175 (-2600 3625)(-2600 4375);
WIRE 16 2175 (-2600 4375)(-2200 4375);
WIRE 16 -1 (-2875 3525)(-2875 3725);
WIRE 16 -1 (-2500 3725)(-2875 3725);
WIRE 16 -1 (-3275 3725)(-2875 3725);
FORCEPROP 2 LAST SIG_NAME H_CPU1_MEMKLM_MEMHOT_LVT3_K_N
J 0
(-3250 3735);
DISPLAY 0.617021 (-3250 3735);
PAINT ORANGE (-3250 3735);
FORCEPROP 2 LASTPROP $XRERR UNIQUE?
J 0
(-3490 3735);
DISPLAY 0.638298 (-3490 3735);
PAINT MONO (-3490 3735);
DISPLAY INVISIBLE (-3490 3735);
WIRE 16 -1 (-2300 3725)(-1450 3725);
FORCEPROP 2 LAST SIG_NAME H_CPU1_MEMKLM_MEMHOT_LVT3_N
J 0
(-2160 3735);
DISPLAY 0.617021 (-2160 3735);
PAINT ORANGE (-2160 3735);
WIRE 16 -1 (-3150 4075)(-2500 4075);
WIRE 16 -1 (-3150 4500)(-3150 4075);
WIRE 16 -1 (-3275 4075)(-3150 4075);
FORCEPROP 2 LAST SIG_NAME H_CPU0_MEMDEF_MEMHOT_LVT3_K_N
J 0
(-3250 4085);
DISPLAY 0.617021 (-3250 4085);
PAINT ORANGE (-3250 4085);
FORCEPROP 2 LASTPROP $XRERR UNIQUE?
J 0
(-3490 4085);
DISPLAY 0.638298 (-3490 4085);
PAINT MONO (-3490 4085);
DISPLAY INVISIBLE (-3490 4085);
WIRE 16 -1 (-2850 4500)(-2850 4250);
WIRE 16 -1 (-2500 4250)(-2850 4250);
WIRE 16 -1 (-3275 4250)(-2850 4250);
FORCEPROP 2 LAST SIG_NAME H_CPU0_MEMABC_MEMHOT_LVT3_K_N
J 0
(-3250 4260);
DISPLAY 0.617021 (-3250 4260);
PAINT ORANGE (-3250 4260);
FORCEPROP 2 LASTPROP $XRERR UNIQUE?
J 0
(-3490 4260);
DISPLAY 0.638298 (-3490 4260);
PAINT MONO (-3490 4260);
DISPLAY INVISIBLE (-3490 4260);
WIRE 16 -1 (-2300 4075)(-1450 4075);
FORCEPROP 2 LAST SIG_NAME H_CPU0_MEMDEF_MEMHOT_LVT3_N
J 0
(-2160 4085);
DISPLAY 0.617021 (-2160 4085);
PAINT ORANGE (-2160 4085);
WIRE 16 -1 (-2300 4250)(-1450 4250);
FORCEPROP 2 LAST SIG_NAME H_CPU0_MEMABC_MEMHOT_LVT3_N
J 0
(-2160 4260);
DISPLAY 0.617021 (-2160 4260);
PAINT ORANGE (-2160 4260);
WIRE 16 -1 (-2300 3900)(-1450 3900);
FORCEPROP 2 LAST SIG_NAME H_CPU1_MEMGHJ_MEMHOT_LVT3_N
J 0
(-2160 3910);
DISPLAY 0.617021 (-2160 3910);
PAINT ORANGE (-2160 3910);
WIRE 16 -1 (-6600 975)(-5300 975);
FORCEPROP 2 LAST SIG_NAME H_CPU1_MEMKLM_MEMHOT_PCH_N
J 0
(-6375 985);
DISPLAY 0.617021 (-6375 985);
PAINT ORANGE (-6375 985);
WIRE 16 -1 (-6800 1825)(-7050 1825);
WIRE 16 -1 (-7050 1825)(-7050 2025);
WIRE 16 -1 (-7050 2025)(-6800 2025);
WIRE 16 -1 (-7950 2025)(-7050 2025);
FORCEPROP 2 LAST SIG_NAME H_CPU0_MEMDEF_MEMHOT_LVT3_N
J 0
(-7910 2035);
DISPLAY 0.617021 (-7910 2035);
PAINT ORANGE (-7910 2035);
WIRE 16 -1 (-7175 3600)(-7175 3900);
WIRE 16 -1 (-7050 3900)(-7175 3900);
WIRE 16 -1 (-8250 3900)(-8250 3375);
WIRE 16 -1 (-7175 3900)(-8250 3900);
WIRE 16 -1 (-8325 3900)(-8250 3900);
WIRE 16 -1 (-8325 4550)(-8325 3900);
WIRE 16 -1 (-8475 3900)(-8325 3900);
FORCEPROP 2 LAST SIG_NAME H_CPU1_MEMGHJ_MEMHOT_G_N
J 0
(-8460 3910);
DISPLAY 0.617021 (-8460 3910);
PAINT ORANGE (-8460 3910);
WIRE 16 -1 (-7450 3600)(-7450 3750);
WIRE 16 -1 (-7050 3750)(-7450 3750);
WIRE 16 -1 (-8350 3750)(-8350 3375);
WIRE 16 -1 (-7450 3750)(-8350 3750);
WIRE 16 -1 (-8425 3750)(-8350 3750);
WIRE 16 -1 (-8425 4550)(-8425 3750);
WIRE 16 -1 (-8475 3750)(-8425 3750);
FORCEPROP 2 LAST SIG_NAME H_CPU1_MEMKLM_MEMHOT_G_N
J 0
(-8460 3760);
DISPLAY 0.617021 (-8460 3760);
PAINT ORANGE (-8460 3760);
WIRE 16 -1 (-2850 4700)(-2850 5125);
WIRE 16 -1 (-7450 5125)(-2850 5125);
FORCEPROP 2 LAST SIG_NAME H_CPU0_MEMABC_MEMHOT_G_PCH_N
J 0
(-5860 5135);
DISPLAY 0.617021 (-5860 5135);
PAINT ORANGE (-5860 5135);
FORCEPROP 2 LASTPROP $XRERR UNIQUE?
J 0
(-6100 5135);
DISPLAY 0.638298 (-6100 5135);
PAINT MONO (-6100 5135);
DISPLAY INVISIBLE (-6100 5135);
WIRE 16 -1 (-7450 4625)(-7450 5125);
WIRE 16 -1 (-3525 3900)(-3475 3900);
WIRE 16 -1 (-3525 3950)(-3525 3900);
WIRE 16 -1 (-4950 3950)(-3525 3950);
FORCEPROP 2 LAST SIG_NAME H_CPU1_GHJ_MEMHOT_LVT3_R_N
J 0
(-4860 3960);
DISPLAY 0.617021 (-4860 3960);
PAINT ORANGE (-4860 3960);
FORCEPROP 2 LASTPROP $XRERR UNIQUE?
J 0
(-5100 3960);
DISPLAY 0.638298 (-5100 3960);
PAINT MONO (-5100 3960);
DISPLAY INVISIBLE (-5100 3960);
WIRE 16 -1 (-3600 4050)(-4950 4050);
FORCEPROP 2 LAST SIG_NAME H_CPU0_ABC_MEMHOT_LVT3_R_N
J 0
(-4860 4060);
DISPLAY 0.617021 (-4860 4060);
PAINT ORANGE (-4860 4060);
FORCEPROP 2 LASTPROP $XRERR UNIQUE?
J 0
(-5100 4060);
DISPLAY 0.638298 (-5100 4060);
PAINT MONO (-5100 4060);
DISPLAY INVISIBLE (-5100 4060);
WIRE 16 -1 (-3600 4250)(-3600 4050);
WIRE 16 -1 (-3600 4250)(-3475 4250);
WIRE 16 2175 (-3650 3225)(-2650 3225);
WIRE 16 2175 (-3650 4800)(-3650 3225);
WIRE 16 2175 (-2650 3225)(-2650 4800);
WIRE 16 2175 (-2650 4800)(-3650 4800);
WIRE 16 2175 (-7575 3250)(-6650 3250);
WIRE 16 2175 (-7575 4725)(-7575 3250);
WIRE 16 2175 (-6650 3250)(-6650 4725);
WIRE 16 2175 (-6650 4725)(-7575 4725);
WIRE 16 -1 (-4200 2300)(-4200 1200);
WIRE 16 -1 (-4525 2300)(-4200 2300);
WIRE 16 -1 (-4525 1200)(-4200 1200);
WIRE 16 -1 (-3900 2300)(-4200 2300);
WIRE 16 -1 (-3900 1200)(-4200 1200);
WIRE 16 -1 (-3900 2200)(-3900 1200);
WIRE 16 -1 (-3900 2300)(-3900 2200);
WIRE 16 -1 (-4525 2200)(-4525 1200);
WIRE 16 -1 (-4525 2300)(-4525 2200);
WIRE 16 -1 (-4525 2200)(-3900 2200);
DOT 1 (-2550 1800);
DOT 1 (-2550 1375);
DOT 1 (-4525 2200);
DOT 1 (-4200 1200);
DOT 1 (-4200 2300);
DOT 1 (-3900 2200);
DOT 1 (-2850 4250);
DOT 1 (-2875 3725);
DOT 1 (-3150 4075);
DOT 1 (-3175 3900);
DOT 1 (-4775 4825);
DOT 1 (-7450 4225);
DOT 1 (-7925 4825);
DOT 1 (-7800 4225);
DOT 1 (-7875 4225);
DOT 1 (-5900 3700);
DOT 1 (-5900 3650);
DOT 1 (-7025 2475);
DOT 1 (-7175 4050);
DOT 1 (-7175 3900);
DOT 1 (-7450 3750);
DOT 1 (-7900 4050);
DOT 1 (-7975 4050);
DOT 1 (-7850 3025);
DOT 1 (-7050 2025);
DOT 1 (-7050 1600);
DOT 1 (-7050 1175);
DOT 1 (-8375 4825);
DOT 1 (-8250 3900);
DOT 1 (-8325 3900);
DOT 1 (-8350 3750);
DOT 1 (-8425 3750);
DOT 1 (-8300 3025);
DOT 1 (-2550 1850);
DOT 1 (-2925 1800);
FORCENOTE
TARGET 0.7V
(-2225 1900) 0;
DISPLAY LEFT (-2225 1900);
DISPLAY 1.021277 (-2225 1900);
PAINT PURPLE (-2225 1900);
FORCENOTE
IE ONLY (NO BMC)
(-4500 2325) 0;
DISPLAY LEFT (-4500 2325);
DISPLAY 1.021277 (-4500 2325);
PAINT PURPLE (-4500 2325);
FORCENOTE
STUFF
(-4150 2225) 0;
DISPLAY LEFT (-4150 2225);
DISPLAY 1.021277 (-4150 2225);
PAINT PURPLE (-4150 2225);
FORCENOTE
UNSTUFF
(-4500 2225) 0;
DISPLAY LEFT (-4500 2225);
DISPLAY 1.021277 (-4500 2225);
PAINT PURPLE (-4500 2225);
FORCENOTE
R9G33
(-4475 1675) 0;
DISPLAY LEFT (-4475 1675);
DISPLAY 1.021277 (-4475 1675);
PAINT PURPLE (-4475 1675);
FORCENOTE
R1U59
(-4475 1750) 0;
DISPLAY LEFT (-4475 1750);
DISPLAY 1.021277 (-4475 1750);
PAINT PURPLE (-4475 1750);
FORCENOTE
R9G32
(-4475 1600) 0;
DISPLAY LEFT (-4475 1600);
DISPLAY 1.021277 (-4475 1600);
PAINT PURPLE (-4475 1600);
FORCENOTE
R9G28
(-4475 1525) 0;
DISPLAY LEFT (-4475 1525);
DISPLAY 1.021277 (-4475 1525);
PAINT PURPLE (-4475 1525);
FORCENOTE
R2U47
(-4475 1450) 0;
DISPLAY LEFT (-4475 1450);
DISPLAY 1.021277 (-4475 1450);
PAINT PURPLE (-4475 1450);
FORCENOTE
R9G29
(-4475 1375) 0;
DISPLAY LEFT (-4475 1375);
DISPLAY 1.021277 (-4475 1375);
PAINT PURPLE (-4475 1375);
FORCENOTE
R2U46
(-4475 1225) 0;
DISPLAY LEFT (-4475 1225);
DISPLAY 1.021277 (-4475 1225);
PAINT PURPLE (-4475 1225);
FORCENOTE
U9G1
(-4475 2125) 0;
DISPLAY LEFT (-4475 2125);
DISPLAY 1.021277 (-4475 2125);
PAINT PURPLE (-4475 2125);
FORCENOTE
R1U54
(-4475 1300) 0;
DISPLAY LEFT (-4475 1300);
DISPLAY 1.021277 (-4475 1300);
PAINT PURPLE (-4475 1300);
FORCENOTE
R1U60
(-4475 1825) 0;
DISPLAY LEFT (-4475 1825);
DISPLAY 1.021277 (-4475 1825);
PAINT PURPLE (-4475 1825);
FORCENOTE
R9G34
(-4475 2050) 0;
DISPLAY LEFT (-4475 2050);
DISPLAY 1.021277 (-4475 2050);
PAINT PURPLE (-4475 2050);
FORCENOTE
R1U53
(-4475 1900) 0;
DISPLAY LEFT (-4475 1900);
DISPLAY 1.021277 (-4475 1900);
PAINT PURPLE (-4475 1900);
FORCENOTE
R1U58
(-4475 1975) 0;
DISPLAY LEFT (-4475 1975);
DISPLAY 1.021277 (-4475 1975);
PAINT PURPLE (-4475 1975);
FORCENOTE
R9G30
(-4150 1450) 0;
DISPLAY LEFT (-4150 1450);
DISPLAY 1.021277 (-4150 1450);
PAINT PURPLE (-4150 1450);
FORCENOTE
R7D35
(-4150 1375) 0;
DISPLAY LEFT (-4150 1375);
DISPLAY 1.021277 (-4150 1375);
PAINT PURPLE (-4150 1375);
FORCENOTE
R2U45
(-4150 1300) 0;
DISPLAY LEFT (-4150 1300);
DISPLAY 1.021277 (-4150 1300);
PAINT PURPLE (-4150 1300);
FORCENOTE
R3N30
(-4150 1525) 0;
DISPLAY LEFT (-4150 1525);
DISPLAY 1.021277 (-4150 1525);
PAINT PURPLE (-4150 1525);
FORCENOTE
R1U55
(-4150 1900) 0;
DISPLAY LEFT (-4150 1900);
DISPLAY 1.021277 (-4150 1900);
PAINT PURPLE (-4150 1900);
FORCENOTE
R9G27
(-4150 1825) 0;
DISPLAY LEFT (-4150 1825);
DISPLAY 1.021277 (-4150 1825);
PAINT PURPLE (-4150 1825);
FORCENOTE
R1U61
(-4150 1600) 0;
DISPLAY LEFT (-4150 1600);
DISPLAY 1.021277 (-4150 1600);
PAINT PURPLE (-4150 1600);
FORCENOTE
R2U49
(-4150 1675) 0;
DISPLAY LEFT (-4150 1675);
DISPLAY 1.021277 (-4150 1675);
PAINT PURPLE (-4150 1675);
FORCENOTE
R1U57
(-4150 1750) 0;
DISPLAY LEFT (-4150 1750);
DISPLAY 1.021277 (-4150 1750);
PAINT PURPLE (-4150 1750);
FORCENOTE
R2U51
(-4150 2125) 0;
DISPLAY LEFT (-4150 2125);
DISPLAY 1.021277 (-4150 2125);
PAINT PURPLE (-4150 2125);
FORCENOTE
ROOM=PROC_SIDEBAND
(-9000 575) 0;
DISPLAY LEFT (-9000 575);
DISPLAY 1.021277 (-9000 575);
PAINT PURPLE (-9000 575);
FORCENOTE
R1U62
(-4150 2050) 0;
DISPLAY LEFT (-4150 2050);
DISPLAY 1.021277 (-4150 2050);
PAINT PURPLE (-4150 2050);
FORCENOTE
R1U56
(-4150 1975) 0;
DISPLAY LEFT (-4150 1975);
DISPLAY 1.021277 (-4150 1975);
PAINT PURPLE (-4150 1975);
FORCENOTE
TP FAB3 CHANGE R1U43 AND CONNECT TO P3V3 0805
(-2500 1825) 0;
DISPLAY LEFT (-2500 1825);
DISPLAY 1.021277 (-2500 1825);
PAINT RED (-2500 1825);
FORCENOTE
TP FAB3 ADD R1W35 0803
(-3775 2450) 0;
DISPLAY LEFT (-3775 2450);
DISPLAY 1.021277 (-3775 2450);
PAINT RED (-3775 2450);
QUIT
